FILE_TYPE = MACRO_DRAWING;
SET COLOR_WIRE YELLOW;
SET COLOR_PROP ORANGE;
SET COLOR_DOT WHITE;
SET COLOR_ARC YELLOW;
SET COLOR_BODY GREEN;
SET COLOR_NOTE PURPLE;
SET PROP_DISPLAY VALUE;
SET PAGE_NUMBER P182;
FORCEADD UNIVERSAL_GND..1
(-2925 5925);
FORCEPROP 3 LASTPIN (-2925 5975) SIG_NAME GND\g
J 0
(-2915 5985);
DISPLAY 0.659574 (-2915 5985);
PAINT MONO (-2915 5985);
DISPLAY INVISIBLE (-2915 5985);
FORCEPROP 2 LAST CDS_LIB pure_quanta_power
J 0
(-2925 5925);
DISPLAY INVISIBLE (-2925 5925);
FORCEPROP 1 LAST PATH I10
J 0
(-2850 5925);
DISPLAY 0.872340 (-2850 5925);
PAINT AQUA (-2850 5925);
DISPLAY INVISIBLE (-2850 5925);
FORCEPROP 1 LAST HDL_POWER GND
J 1
(-2900 5850);
DISPLAY 0.872340 (-2900 5850);
PAINT GREEN (-2900 5850);
DISPLAY INVISIBLE (-2900 5850);
FORCEADD Q_CAP..1
(-5300 475);
FORCEPROP 1 LAST LOCATION PC5
J 0
(-5250 575);
DISPLAY 0.489362 (-5250 575);
PAINT SKYBLUE (-5250 575);
FORCEPROP 2 LAST SEC 1
J 0
(-5250 675);
DISPLAY 0.680851 (-5250 675);
PAINT MONO (-5250 675);
DISPLAY INVISIBLE (-5250 675);
FORCEPROP 1 LASTPIN (-5300 575) $PN 1
J 0
(-5290 555);
DISPLAY 0.489362 (-5290 555);
PAINT MONO (-5290 555);
FORCEPROP 1 LASTPIN (-5300 375) $PN 2
J 0
(-5290 355);
DISPLAY 0.489362 (-5290 355);
PAINT MONO (-5290 355);
FORCEPROP 1 LAST MATERIAL X7R
J 0
(-5250 375);
DISPLAY 0.489362 (-5250 375);
PAINT SKYBLUE (-5250 375);
FORCEPROP 1 LAST TOLERANCE 10%
J 0
(-5250 425);
DISPLAY 0.489362 (-5250 425);
PAINT SKYBLUE (-5250 425);
FORCEPROP 1 LAST VALUE 0.1UF
J 0
(-5250 525);
DISPLAY 0.489362 (-5250 525);
PAINT SKYBLUE (-5250 525);
FORCEPROP 1 LAST PART_NUMBER CH4104K1B00
J 0
(-5250 325);
DISPLAY 0.489362 (-5250 325);
PAINT SKYBLUE (-5250 325);
FORCEPROP 1 LAST VOLTAGE 25V
J 0
(-5250 475);
DISPLAY 0.489362 (-5250 475);
PAINT SKYBLUE (-5250 475);
FORCEPROP 1 LAST PACK_TYPE 0402
J 0
(-5250 275);
DISPLAY 0.489362 (-5250 275);
PAINT SKYBLUE (-5250 275);
FORCEPROP 2 LAST SEC_TYPE 0402
J 0
(-5250 675);
DISPLAY 1.021277 (-5250 675);
DISPLAY INVISIBLE (-5250 675);
FORCEPROP 2 LAST CDS_LIB pure_quanta
J 0
(-5300 475);
DISPLAY INVISIBLE (-5300 475);
FORCEPROP 1 LAST PATH I100
J 0
(-5250 625);
DISPLAY 0.978723 (-5250 625);
PAINT WHITE (-5250 625);
DISPLAY INVISIBLE (-5250 625);
FORCEADD Q_RES..1
(-5950 650);
FORCEPROP 1 LAST LOCATION PR125
J 0
(-5975 700);
DISPLAY 0.489362 (-5975 700);
PAINT SKYBLUE (-5975 700);
FORCEPROP 0 LAST $SEC 1
J 0
(-6000 750);
DISPLAY 0.680851 (-6000 750);
PAINT MONO (-6000 750);
DISPLAY INVISIBLE (-6000 750);
FORCEPROP 0 LAST CDS_SEC 1
J 0
(-6000 750);
DISPLAY 1.021277 (-6000 750);
DISPLAY INVISIBLE (-6000 750);
FORCEPROP 1 LASTPIN (-6050 650) $PN 1
J 0
(-6038 662);
DISPLAY 0.489362 (-6038 662);
PAINT MONO (-6038 662);
FORCEPROP 1 LASTPIN (-5850 650) $PN 2
J 0
(-5888 662);
DISPLAY 0.489362 (-5888 662);
PAINT MONO (-5888 662);
FORCEPROP 1 LAST WATTAGE 1/16W
J 0
(-5850 600);
DISPLAY 0.489362 (-5850 600);
PAINT SKYBLUE (-5850 600);
FORCEPROP 1 LAST MATERIAL CHIP
J 0
(-6200 575);
DISPLAY 0.489362 (-6200 575);
PAINT SKYBLUE (-6200 575);
FORCEPROP 1 LAST TOLERANCE 5%
J 0
(-5825 675);
DISPLAY 0.489362 (-5825 675);
PAINT SKYBLUE (-5825 675);
FORCEPROP 1 LAST VALUE 0
J 2
(-6075 675);
DISPLAY 0.489362 (-6075 675);
PAINT SKYBLUE (-6075 675);
FORCEPROP 1 LAST PART_NUMBER CS00002JB38
J 0
(-6200 600);
DISPLAY 0.489362 (-6200 600);
PAINT SKYBLUE (-6200 600);
FORCEPROP 1 LAST PACK_TYPE 0402LF
J 0
(-5850 575);
DISPLAY 0.489362 (-5850 575);
PAINT SKYBLUE (-5850 575);
FORCEPROP 2 LAST CDS_LIB pure_quanta
J 0
(-5950 650);
DISPLAY INVISIBLE (-5950 650);
FORCEPROP 1 LAST PATH I101
J 0
(-6000 800);
DISPLAY 0.978723 (-6000 800);
PAINT WHITE (-6000 800);
DISPLAY INVISIBLE (-6000 800);
FORCEADD UNIVERSAL_GND..1
(-5300 250);
FORCEPROP 3 LASTPIN (-5300 300) SIG_NAME GND\g
J 0
(-5290 310);
DISPLAY 0.659574 (-5290 310);
PAINT MONO (-5290 310);
DISPLAY INVISIBLE (-5290 310);
FORCEPROP 2 LAST CDS_LIB pure_quanta_power
J 0
(-5300 250);
DISPLAY INVISIBLE (-5300 250);
FORCEPROP 1 LAST PATH I102
J 0
(-5225 250);
DISPLAY 0.872340 (-5225 250);
PAINT AQUA (-5225 250);
DISPLAY INVISIBLE (-5225 250);
FORCEPROP 1 LAST HDL_POWER GND
J 1
(-5275 175);
DISPLAY 0.872340 (-5275 175);
PAINT GREEN (-5275 175);
DISPLAY INVISIBLE (-5275 175);
FORCEADD Q_RES..1
(-7200 825);
FORCEPROP 1 LAST LOCATION PR113
J 0
(-7250 875);
DISPLAY 0.489362 (-7250 875);
PAINT SKYBLUE (-7250 875);
FORCEPROP 0 LAST $SEC 1
J 0
(-7250 925);
DISPLAY 0.680851 (-7250 925);
PAINT MONO (-7250 925);
DISPLAY INVISIBLE (-7250 925);
FORCEPROP 0 LAST CDS_SEC 1
J 0
(-7250 925);
DISPLAY 1.021277 (-7250 925);
DISPLAY INVISIBLE (-7250 925);
FORCEPROP 1 LASTPIN (-7300 825) $PN 1
J 0
(-7288 837);
DISPLAY 0.489362 (-7288 837);
PAINT MONO (-7288 837);
FORCEPROP 1 LASTPIN (-7100 825) $PN 2
J 0
(-7138 837);
DISPLAY 0.489362 (-7138 837);
PAINT MONO (-7138 837);
FORCEPROP 1 LAST WATTAGE 1/16W
J 0
(-7075 775);
DISPLAY 0.489362 (-7075 775);
PAINT SKYBLUE (-7075 775);
FORCEPROP 1 LAST MATERIAL CHIP
J 0
(-7500 750);
DISPLAY 0.489362 (-7500 750);
PAINT SKYBLUE (-7500 750);
FORCEPROP 1 LAST TOLERANCE 1%
J 0
(-7050 850);
DISPLAY 0.489362 (-7050 850);
PAINT SKYBLUE (-7050 850);
FORCEPROP 1 LAST VALUE 40.2K
J 2
(-7350 850);
DISPLAY 0.489362 (-7350 850);
PAINT SKYBLUE (-7350 850);
FORCEPROP 1 LAST PART_NUMBER TMP_QCS34022FB15
J 0
(-7500 775);
DISPLAY 0.489362 (-7500 775);
PAINT SKYBLUE (-7500 775);
FORCEPROP 1 LAST PACK_TYPE 0402LF
J 0
(-7075 750);
DISPLAY 0.489362 (-7075 750);
PAINT SKYBLUE (-7075 750);
FORCEPROP 2 LAST CDS_LIB pure_quanta
J 0
(-7200 825);
DISPLAY INVISIBLE (-7200 825);
FORCEPROP 1 LAST PATH I104
J 0
(-7250 975);
DISPLAY 0.978723 (-7250 975);
PAINT WHITE (-7250 975);
DISPLAY INVISIBLE (-7250 975);
FORCEADD Q_RES..2
(-6450 650);
FORCEPROP 1 LAST LOCATION PR3
J 0
(-6400 750);
DISPLAY 0.489362 (-6400 750);
PAINT SKYBLUE (-6400 750);
FORCEPROP 2 LAST SEC 1
J 0
(-6400 875);
DISPLAY 0.680851 (-6400 875);
PAINT MONO (-6400 875);
DISPLAY INVISIBLE (-6400 875);
FORCEPROP 1 LASTPIN (-6450 750) $PN 1
J 0
(-6445 712);
DISPLAY 0.489362 (-6445 712);
PAINT MONO (-6445 712);
FORCEPROP 1 LASTPIN (-6450 550) $PN 2
J 0
(-6445 560);
DISPLAY 0.489362 (-6445 560);
PAINT MONO (-6445 560);
FORCEPROP 1 LAST WATTAGE 1/16W
J 0
(-6400 600);
DISPLAY 0.489362 (-6400 600);
PAINT SKYBLUE (-6400 600);
FORCEPROP 1 LAST MATERIAL CHIP
J 0
(-6400 550);
DISPLAY 0.489362 (-6400 550);
PAINT SKYBLUE (-6400 550);
FORCEPROP 1 LAST TOLERANCE 1%
J 0
(-6400 650);
DISPLAY 0.489362 (-6400 650);
PAINT SKYBLUE (-6400 650);
FORCEPROP 1 LAST VALUE 10K
J 0
(-6400 700);
DISPLAY 0.489362 (-6400 700);
PAINT SKYBLUE (-6400 700);
FORCEPROP 1 LAST PART_NUMBER TMP_QCS31002FB26
J 0
(-6400 500);
DISPLAY 0.489362 (-6400 500);
PAINT SKYBLUE (-6400 500);
FORCEPROP 1 LAST PACK_TYPE 0402LF
J 0
(-6400 450);
DISPLAY 0.489362 (-6400 450);
PAINT SKYBLUE (-6400 450);
FORCEPROP 2 LAST CDS_LIB pure_quanta
J 0
(-6450 650);
DISPLAY INVISIBLE (-6450 650);
FORCEPROP 2 LAST SEC_TYPE 0402LF
J 0
(-6400 875);
DISPLAY 1.021277 (-6400 875);
DISPLAY INVISIBLE (-6400 875);
FORCEPROP 1 LAST PATH I105
J 0
(-6400 825);
DISPLAY 0.978723 (-6400 825);
PAINT WHITE (-6400 825);
DISPLAY INVISIBLE (-6400 825);
FORCEADD UNIVERSAL_GND..1
(-6450 375);
FORCEPROP 3 LASTPIN (-6450 425) SIG_NAME GND\g
J 0
(-6440 435);
DISPLAY 0.659574 (-6440 435);
PAINT MONO (-6440 435);
DISPLAY INVISIBLE (-6440 435);
FORCEPROP 2 LAST CDS_LIB pure_quanta_power
J 0
(-6450 375);
DISPLAY INVISIBLE (-6450 375);
FORCEPROP 1 LAST PATH I107
J 0
(-6375 375);
DISPLAY 0.872340 (-6375 375);
PAINT AQUA (-6375 375);
DISPLAY INVISIBLE (-6375 375);
FORCEPROP 1 LAST HDL_POWER GND
J 1
(-6425 300);
DISPLAY 0.872340 (-6425 300);
PAINT GREEN (-6425 300);
DISPLAY INVISIBLE (-6425 300);
FORCEADD UNIVERSAL_GND..1
(-6875 400);
FORCEPROP 3 LASTPIN (-6875 450) SIG_NAME GND\g
J 0
(-6865 460);
DISPLAY 0.659574 (-6865 460);
PAINT MONO (-6865 460);
DISPLAY INVISIBLE (-6865 460);
FORCEPROP 2 LAST CDS_LIB pure_quanta_power
J 0
(-6875 400);
DISPLAY INVISIBLE (-6875 400);
FORCEPROP 1 LAST PATH I108
J 0
(-6800 400);
DISPLAY 0.872340 (-6800 400);
PAINT AQUA (-6800 400);
DISPLAY INVISIBLE (-6800 400);
FORCEPROP 1 LAST HDL_POWER GND
J 1
(-6850 325);
DISPLAY 0.872340 (-6850 325);
PAINT GREEN (-6850 325);
DISPLAY INVISIBLE (-6850 325);
FORCEADD VCC_CORE..1
(-7550 925);
FORCEPROP 3 LASTPIN (-7550 875) SIG_NAME P5V_STBY\g
J 0
(-7540 885);
DISPLAY 0.659574 (-7540 885);
PAINT MONO (-7540 885);
DISPLAY INVISIBLE (-7540 885);
FORCEPROP 1 LAST HDL_POWER P5V_STBY
J 1
(-7550 975);
DISPLAY 0.489362 (-7550 975);
PAINT GREEN (-7550 975);
FORCEPROP 2 LAST CDS_LIB pure_quanta_power
J 0
(-7550 925);
DISPLAY INVISIBLE (-7550 925);
FORCEPROP 1 LAST PATH I109
J 0
(-7500 950);
DISPLAY 0.872340 (-7500 950);
PAINT AQUA (-7500 950);
DISPLAY INVISIBLE (-7500 950);
FORCEADD Q_CAP..1
(-6875 650);
FORCEPROP 1 LAST LOCATION PC193
J 0
(-6800 750);
DISPLAY 0.489362 (-6800 750);
PAINT SKYBLUE (-6800 750);
FORCEPROP 0 LAST $SEC 1
J 0
(-6825 775);
DISPLAY 0.680851 (-6825 775);
PAINT MONO (-6825 775);
DISPLAY INVISIBLE (-6825 775);
FORCEPROP 0 LAST CDS_SEC 1
J 0
(-6825 775);
DISPLAY 1.021277 (-6825 775);
DISPLAY INVISIBLE (-6825 775);
FORCEPROP 1 LASTPIN (-6875 750) $PN 1
J 0
(-6865 730);
DISPLAY 0.489362 (-6865 730);
PAINT MONO (-6865 730);
FORCEPROP 1 LASTPIN (-6875 550) $PN 2
J 0
(-6865 530);
DISPLAY 0.489362 (-6865 530);
PAINT MONO (-6865 530);
FORCEPROP 1 LAST MATERIAL X7R
J 0
(-6800 550);
DISPLAY 0.489362 (-6800 550);
PAINT SKYBLUE (-6800 550);
FORCEPROP 1 LAST TOLERANCE 10%
J 0
(-6800 600);
DISPLAY 0.489362 (-6800 600);
PAINT SKYBLUE (-6800 600);
FORCEPROP 1 LAST VALUE 0.1UF
J 0
(-6800 700);
DISPLAY 0.489362 (-6800 700);
PAINT SKYBLUE (-6800 700);
FORCEPROP 1 LAST PART_NUMBER CH4104K1B00
J 0
(-6800 500);
DISPLAY 0.489362 (-6800 500);
PAINT SKYBLUE (-6800 500);
FORCEPROP 1 LAST VOLTAGE 25V
J 0
(-6800 650);
DISPLAY 0.489362 (-6800 650);
PAINT SKYBLUE (-6800 650);
FORCEPROP 1 LAST PACK_TYPE 0402
J 0
(-6800 450);
DISPLAY 0.489362 (-6800 450);
PAINT SKYBLUE (-6800 450);
FORCEPROP 2 LAST CDS_LIB pure_quanta
J 0
(-6875 650);
DISPLAY INVISIBLE (-6875 650);
FORCEPROP 1 LAST PATH I118
J 0
(-6825 800);
DISPLAY 0.978723 (-6825 800);
PAINT WHITE (-6825 800);
DISPLAY INVISIBLE (-6825 800);
FORCEADD UNIVERSAL_GND..1
(-2925 5425);
FORCEPROP 3 LASTPIN (-2925 5475) SIG_NAME GND\g
J 0
(-2915 5485);
DISPLAY 0.659574 (-2915 5485);
PAINT MONO (-2915 5485);
DISPLAY INVISIBLE (-2915 5485);
FORCEPROP 2 LAST CDS_LIB pure_quanta_power
J 0
(-2925 5425);
DISPLAY INVISIBLE (-2925 5425);
FORCEPROP 1 LAST PATH I12
J 0
(-2850 5425);
DISPLAY 0.872340 (-2850 5425);
PAINT AQUA (-2850 5425);
DISPLAY INVISIBLE (-2850 5425);
FORCEPROP 1 LAST HDL_POWER GND
J 1
(-2900 5350);
DISPLAY 0.872340 (-2900 5350);
PAINT GREEN (-2900 5350);
DISPLAY INVISIBLE (-2900 5350);
FORCEADD OFFPAGE..4
R 4
(-6625 5950);
FORCEPROP 2 LAST $XR0 81 
J 0
(-6846 5950);
DISPLAY 0.638298 (-6846 5950);
PAINT MONO (-6846 5950);
FORCEPROP 1 LAST COMMENT_BODY TRUE
R 2
J 0
(-6600 6050);
DISPLAY 0.872340 (-6600 6050);
PAINT GREEN (-6600 6050);
DISPLAY INVISIBLE (-6600 6050);
FORCEPROP 2 LAST CDS_LIB standard
R 2
J 2
(-6625 5950);
DISPLAY INVISIBLE (-6625 5950);
FORCEPROP 2 LAST PATH I127
R 2
J 2
(-6575 5875);
DISPLAY 1.021277 (-6575 5875);
DISPLAY INVISIBLE (-6575 5875);
FORCEPROP 1 LAST OFFPAGE TRUE
R 2
J 0
(-6950 6075);
DISPLAY 0.872340 (-6950 6075);
PAINT GREEN (-6950 6075);
DISPLAY INVISIBLE (-6950 6075);
FORCEADD Q_CAP..1
(-2925 5650);
FORCEPROP 1 LAST LOCATION PC199
J 0
(-2875 5750);
DISPLAY 0.489362 (-2875 5750);
PAINT SKYBLUE (-2875 5750);
FORCEPROP 0 LAST $SEC 1
J 0
(-2875 5775);
DISPLAY 0.680851 (-2875 5775);
PAINT MONO (-2875 5775);
DISPLAY INVISIBLE (-2875 5775);
FORCEPROP 0 LAST CDS_SEC 1
J 0
(-2875 5775);
DISPLAY 1.021277 (-2875 5775);
DISPLAY INVISIBLE (-2875 5775);
FORCEPROP 1 LASTPIN (-2925 5750) $PN 1
J 0
(-2915 5730);
DISPLAY 0.489362 (-2915 5730);
PAINT MONO (-2915 5730);
FORCEPROP 1 LASTPIN (-2925 5550) $PN 2
J 0
(-2915 5530);
DISPLAY 0.489362 (-2915 5530);
PAINT MONO (-2915 5530);
FORCEPROP 1 LAST MATERIAL X6S
J 0
(-2875 5550);
DISPLAY 0.489362 (-2875 5550);
PAINT SKYBLUE (-2875 5550);
FORCEPROP 1 LAST TOLERANCE 20%
J 0
(-2875 5600);
DISPLAY 0.489362 (-2875 5600);
PAINT SKYBLUE (-2875 5600);
FORCEPROP 1 LAST VALUE 10UF
J 0
(-2875 5700);
DISPLAY 0.489362 (-2875 5700);
PAINT SKYBLUE (-2875 5700);
FORCEPROP 1 LAST PART_NUMBER CH6101MEB01
J 0
(-2875 5500);
DISPLAY 0.489362 (-2875 5500);
PAINT SKYBLUE (-2875 5500);
FORCEPROP 1 LAST VOLTAGE 6.3V
J 0
(-2875 5650);
DISPLAY 0.489362 (-2875 5650);
PAINT SKYBLUE (-2875 5650);
FORCEPROP 1 LAST PACK_TYPE C0402
J 0
(-2875 5450);
DISPLAY 0.489362 (-2875 5450);
PAINT SKYBLUE (-2875 5450);
FORCEPROP 2 LAST CDS_LIB pure_quanta
J 0
(-2925 5650);
DISPLAY INVISIBLE (-2925 5650);
FORCEPROP 1 LAST PATH I13
J 0
(-2875 5800);
DISPLAY 0.978723 (-2875 5800);
PAINT WHITE (-2875 5800);
DISPLAY INVISIBLE (-2875 5800);
FORCEADD VCC_CORE..1
(-2125 6375);
FORCEPROP 3 LASTPIN (-2125 6325) SIG_NAME P3V3_STBY\g
J 0
(-2115 6335);
DISPLAY 0.659574 (-2115 6335);
PAINT MONO (-2115 6335);
DISPLAY INVISIBLE (-2115 6335);
FORCEPROP 1 LAST HDL_POWER P3V3_STBY
J 1
(-2125 6425);
DISPLAY 0.489362 (-2125 6425);
PAINT GREEN (-2125 6425);
FORCEPROP 2 LAST CDS_LIB pure_quanta_power
J 0
(-2125 6375);
DISPLAY INVISIBLE (-2125 6375);
FORCEPROP 1 LAST PATH I14
J 0
(-2075 6400);
DISPLAY 0.872340 (-2075 6400);
PAINT AQUA (-2075 6400);
DISPLAY INVISIBLE (-2075 6400);
FORCEADD UNIVERSAL_GND..1
R 2
(-5300 2550);
FORCEPROP 3 LASTPIN (-5300 2600) SIG_NAME GND\g
J 0
(-5290 2610);
DISPLAY 0.659574 (-5290 2610);
PAINT MONO (-5290 2610);
DISPLAY INVISIBLE (-5290 2610);
FORCEPROP 2 LAST CDS_LIB pure_quanta_power
J 0
(-5300 2550);
DISPLAY INVISIBLE (-5300 2550);
FORCEPROP 1 LAST PATH I146
J 2
(-5375 2550);
DISPLAY 0.872340 (-5375 2550);
PAINT AQUA (-5375 2550);
DISPLAY INVISIBLE (-5375 2550);
FORCEPROP 1 LAST HDL_POWER GND
J 1
(-5325 2475);
DISPLAY 0.872340 (-5325 2475);
PAINT GREEN (-5325 2475);
DISPLAY INVISIBLE (-5325 2475);
FORCEADD Q_RES..1
(-2500 6275);
FORCEPROP 1 LAST LOCATION PR130
J 0
(-2550 6325);
DISPLAY 0.489362 (-2550 6325);
PAINT SKYBLUE (-2550 6325);
FORCEPROP 0 LAST $SEC 1
J 0
(-2550 6375);
DISPLAY 0.680851 (-2550 6375);
PAINT MONO (-2550 6375);
DISPLAY INVISIBLE (-2550 6375);
FORCEPROP 0 LAST CDS_SEC 1
J 0
(-2550 6375);
DISPLAY 1.021277 (-2550 6375);
DISPLAY INVISIBLE (-2550 6375);
FORCEPROP 1 LASTPIN (-2600 6275) $PN 1
J 0
(-2588 6287);
DISPLAY 0.489362 (-2588 6287);
PAINT MONO (-2588 6287);
FORCEPROP 1 LASTPIN (-2400 6275) $PN 2
J 0
(-2438 6287);
DISPLAY 0.489362 (-2438 6287);
PAINT MONO (-2438 6287);
FORCEPROP 1 LAST WATTAGE 1/16W
J 0
(-2375 6200);
DISPLAY 0.489362 (-2375 6200);
PAINT SKYBLUE (-2375 6200);
FORCEPROP 1 LAST MATERIAL CHIP
J 0
(-2375 6225);
DISPLAY 0.489362 (-2375 6225);
PAINT SKYBLUE (-2375 6225);
FORCEPROP 1 LAST TOLERANCE 1%
J 0
(-2375 6300);
DISPLAY 0.489362 (-2375 6300);
PAINT SKYBLUE (-2375 6300);
FORCEPROP 1 LAST VALUE 1
J 2
(-2650 6300);
DISPLAY 0.489362 (-2650 6300);
PAINT SKYBLUE (-2650 6300);
FORCEPROP 1 LAST PART_NUMBER CS-1002FB23
J 0
(-2675 6225);
DISPLAY 0.489362 (-2675 6225);
PAINT SKYBLUE (-2675 6225);
FORCEPROP 1 LAST PACK_TYPE 0402LF
J 0
(-2675 6200);
DISPLAY 0.489362 (-2675 6200);
PAINT SKYBLUE (-2675 6200);
FORCEPROP 2 LAST CDS_LIB pure_quanta
J 0
(-2500 6275);
DISPLAY INVISIBLE (-2500 6275);
FORCEPROP 1 LAST PATH I148
J 0
(-2550 6425);
DISPLAY 0.978723 (-2550 6425);
PAINT WHITE (-2550 6425);
DISPLAY INVISIBLE (-2550 6425);
FORCEADD OFFPAGE..2
R 2
(-6625 6100);
FORCEPROP 2 LAST $XR1 111 
J 0
(-6999 6100);
DISPLAY 0.638298 (-6999 6100);
PAINT MONO (-6999 6100);
FORCEPROP 2 LAST $XR0 80 
J 0
(-6879 6100);
DISPLAY 0.638298 (-6879 6100);
PAINT MONO (-6879 6100);
FORCEPROP 2 LAST PATH I149
J 0
(-6575 6175);
DISPLAY 1.021277 (-6575 6175);
DISPLAY INVISIBLE (-6575 6175);
FORCEPROP 2 LAST CDS_LIB standard
J 0
(-6625 6100);
DISPLAY INVISIBLE (-6625 6100);
FORCEPROP 1 LAST COMMENT_BODY TRUE
J 2
(-6580 6005);
DISPLAY 0.872340 (-6580 6005);
PAINT GREEN (-6580 6005);
DISPLAY INVISIBLE (-6580 6005);
FORCEPROP 1 LAST OFFPAGE TRUE
J 2
(-6950 5975);
DISPLAY 0.872340 (-6950 5975);
PAINT GREEN (-6950 5975);
DISPLAY INVISIBLE (-6950 5975);
FORCEADD OFFPAGE..5
R 2
(-2725 5800);
FORCEPROP 2 LAST $XR0 184 
J 0
(-2536 5800);
DISPLAY 0.638298 (-2536 5800);
PAINT MONO (-2536 5800);
FORCEPROP 2 LAST PATH I15
J 2
(-2775 5875);
DISPLAY 1.021277 (-2775 5875);
DISPLAY INVISIBLE (-2775 5875);
FORCEPROP 2 LAST CDS_LIB standard
J 2
(-2725 5800);
DISPLAY INVISIBLE (-2725 5800);
FORCEPROP 1 LAST COMMENT_BODY TRUE
J 2
(-2825 5725);
DISPLAY 0.872340 (-2825 5725);
PAINT GREEN (-2825 5725);
DISPLAY INVISIBLE (-2825 5725);
FORCEPROP 1 LAST OFFPAGE TRUE
J 2
(-3050 5675);
DISPLAY 0.872340 (-3050 5675);
PAINT GREEN (-3050 5675);
DISPLAY INVISIBLE (-3050 5675);
FORCEADD VCC_CORE..1
(-6525 6500);
FORCEPROP 3 LASTPIN (-6525 6450) SIG_NAME P3V3_STBY\g
J 0
(-6515 6460);
DISPLAY 0.659574 (-6515 6460);
PAINT MONO (-6515 6460);
DISPLAY INVISIBLE (-6515 6460);
FORCEPROP 1 LAST HDL_POWER P3V3_STBY
J 1
(-6525 6550);
DISPLAY 0.489362 (-6525 6550);
PAINT GREEN (-6525 6550);
FORCEPROP 2 LAST CDS_LIB pure_quanta_power
J 0
(-6525 6500);
DISPLAY INVISIBLE (-6525 6500);
FORCEPROP 1 LAST PATH I150
J 0
(-6475 6525);
DISPLAY 0.872340 (-6475 6525);
PAINT AQUA (-6475 6525);
DISPLAY INVISIBLE (-6475 6525);
FORCEADD Q_RES..1
(-6125 6375);
FORCEPROP 1 LAST LOCATION PR117
J 0
(-6175 6425);
DISPLAY 0.489362 (-6175 6425);
PAINT SKYBLUE (-6175 6425);
FORCEPROP 0 LAST $SEC 1
J 0
(-6175 6475);
DISPLAY 0.680851 (-6175 6475);
PAINT MONO (-6175 6475);
DISPLAY INVISIBLE (-6175 6475);
FORCEPROP 0 LAST CDS_SEC 1
J 0
(-6175 6475);
DISPLAY 1.021277 (-6175 6475);
DISPLAY INVISIBLE (-6175 6475);
FORCEPROP 1 LASTPIN (-6225 6375) $PN 1
J 0
(-6213 6387);
DISPLAY 0.489362 (-6213 6387);
PAINT MONO (-6213 6387);
FORCEPROP 1 LASTPIN (-6025 6375) $PN 2
J 0
(-6063 6387);
DISPLAY 0.489362 (-6063 6387);
PAINT MONO (-6063 6387);
FORCEPROP 1 LAST WATTAGE 1/16W
J 0
(-6025 6325);
DISPLAY 0.489362 (-6025 6325);
PAINT SKYBLUE (-6025 6325);
FORCEPROP 1 LAST MATERIAL CHIP
J 0
(-6450 6275);
DISPLAY 0.489362 (-6450 6275);
PAINT SKYBLUE (-6450 6275);
FORCEPROP 1 LAST TOLERANCE 1%
J 0
(-6000 6400);
DISPLAY 0.489362 (-6000 6400);
PAINT SKYBLUE (-6000 6400);
FORCEPROP 1 LAST VALUE 1K
J 2
(-6275 6400);
DISPLAY 0.489362 (-6275 6400);
PAINT SKYBLUE (-6275 6400);
FORCEPROP 1 LAST PART_NUMBER TMP_QCS21002FB24
J 0
(-6450 6325);
DISPLAY 0.489362 (-6450 6325);
PAINT SKYBLUE (-6450 6325);
FORCEPROP 1 LAST PACK_TYPE 0402LF
J 0
(-6025 6275);
DISPLAY 0.489362 (-6025 6275);
PAINT SKYBLUE (-6025 6275);
FORCEPROP 2 LAST CDS_LIB pure_quanta
J 0
(-6125 6375);
DISPLAY INVISIBLE (-6125 6375);
FORCEPROP 1 LAST PATH I151
J 0
(-6175 6525);
DISPLAY 0.978723 (-6175 6525);
PAINT WHITE (-6175 6525);
DISPLAY INVISIBLE (-6175 6525);
FORCEADD Q_RES..1
(-5900 6100);
FORCEPROP 1 LAST LOCATION PR122
J 0
(-5950 6150);
DISPLAY 0.489362 (-5950 6150);
PAINT SKYBLUE (-5950 6150);
FORCEPROP 0 LAST $SEC 1
J 0
(-5950 6200);
DISPLAY 0.680851 (-5950 6200);
PAINT MONO (-5950 6200);
DISPLAY INVISIBLE (-5950 6200);
FORCEPROP 0 LAST CDS_SEC 1
J 0
(-5950 6200);
DISPLAY 1.021277 (-5950 6200);
DISPLAY INVISIBLE (-5950 6200);
FORCEPROP 1 LASTPIN (-6000 6100) $PN 1
J 0
(-5988 6112);
DISPLAY 0.489362 (-5988 6112);
PAINT MONO (-5988 6112);
FORCEPROP 1 LASTPIN (-5800 6100) $PN 2
J 0
(-5838 6112);
DISPLAY 0.489362 (-5838 6112);
PAINT MONO (-5838 6112);
FORCEPROP 1 LAST WATTAGE 1/16W
J 0
(-5800 6050);
DISPLAY 0.489362 (-5800 6050);
PAINT SKYBLUE (-5800 6050);
FORCEPROP 1 LAST MATERIAL CHIP
J 0
(-6150 6025);
DISPLAY 0.489362 (-6150 6025);
PAINT SKYBLUE (-6150 6025);
FORCEPROP 1 LAST TOLERANCE 5%
J 0
(-5775 6125);
DISPLAY 0.489362 (-5775 6125);
PAINT SKYBLUE (-5775 6125);
FORCEPROP 1 LAST VALUE 0
J 2
(-6025 6125);
DISPLAY 0.489362 (-6025 6125);
PAINT SKYBLUE (-6025 6125);
FORCEPROP 1 LAST PART_NUMBER CS00002JB38
J 0
(-6150 6050);
DISPLAY 0.489362 (-6150 6050);
PAINT SKYBLUE (-6150 6050);
FORCEPROP 1 LAST PACK_TYPE 0402LF
J 0
(-5800 6025);
DISPLAY 0.489362 (-5800 6025);
PAINT SKYBLUE (-5800 6025);
FORCEPROP 2 LAST CDS_LIB pure_quanta
J 0
(-5900 6100);
DISPLAY INVISIBLE (-5900 6100);
FORCEPROP 1 LAST PATH I152
J 0
(-5950 6250);
DISPLAY 0.978723 (-5950 6250);
PAINT WHITE (-5950 6250);
DISPLAY INVISIBLE (-5950 6250);
FORCEADD Q_CAP..2
(-5250 6375);
FORCEPROP 1 LAST LOCATION PC196
J 1
(-5250 6450);
DISPLAY 0.489362 (-5250 6450);
PAINT SKYBLUE (-5250 6450);
FORCEPROP 0 LAST $SEC 1
J 0
(-5250 6525);
DISPLAY 0.680851 (-5250 6525);
PAINT MONO (-5250 6525);
DISPLAY INVISIBLE (-5250 6525);
FORCEPROP 0 LAST CDS_SEC 1
J 0
(-5250 6525);
DISPLAY 1.021277 (-5250 6525);
DISPLAY INVISIBLE (-5250 6525);
FORCEPROP 1 LASTPIN (-5350 6375) $PN 1
J 0
(-5360 6390);
DISPLAY 0.489362 (-5360 6390);
PAINT MONO (-5360 6390);
FORCEPROP 1 LASTPIN (-5150 6375) $PN 2
J 0
(-5165 6390);
DISPLAY 0.489362 (-5165 6390);
PAINT MONO (-5165 6390);
FORCEPROP 1 LAST MATERIAL EMPTY
J 0
(-5525 6250);
DISPLAY 0.489362 (-5525 6250);
PAINT RED (-5525 6250);
FORCEPROP 1 LAST TOLERANCE 5%
J 0
(-5125 6250);
DISPLAY 0.489362 (-5125 6250);
PAINT SKYBLUE (-5125 6250);
FORCEPROP 1 LAST VALUE 1000PF
J 2
(-5375 6425);
DISPLAY 0.489362 (-5375 6425);
PAINT SKYBLUE (-5375 6425);
FORCEPROP 1 LAST PART_NUMBER TMP_QCH21006JB10
J 1
(-5400 6300);
DISPLAY 0.489362 (-5400 6300);
PAINT SKYBLUE (-5400 6300);
FORCEPROP 1 LAST VOLTAGE 50V
J 0
(-5150 6425);
DISPLAY 0.489362 (-5150 6425);
PAINT SKYBLUE (-5150 6425);
FORCEPROP 1 LAST PACK_TYPE 0402
J 0
(-5125 6300);
DISPLAY 0.489362 (-5125 6300);
PAINT SKYBLUE (-5125 6300);
FORCEPROP 2 LAST CDS_LIB pure_quanta
J 0
(-5250 6375);
DISPLAY INVISIBLE (-5250 6375);
FORCEPROP 1 LAST PATH I153
J 0
(-5250 6575);
DISPLAY 0.978723 (-5250 6575);
PAINT WHITE (-5250 6575);
DISPLAY INVISIBLE (-5250 6575);
FORCEADD UNIVERSAL_GND..1
(-5000 6300);
FORCEPROP 3 LASTPIN (-5000 6350) SIG_NAME GND\g
J 0
(-4990 6360);
DISPLAY 0.659574 (-4990 6360);
PAINT MONO (-4990 6360);
DISPLAY INVISIBLE (-4990 6360);
FORCEPROP 2 LAST CDS_LIB pure_quanta_power
J 0
(-5000 6300);
DISPLAY INVISIBLE (-5000 6300);
FORCEPROP 1 LAST PATH I154
J 0
(-4925 6300);
DISPLAY 0.872340 (-4925 6300);
PAINT AQUA (-4925 6300);
DISPLAY INVISIBLE (-4925 6300);
FORCEPROP 1 LAST HDL_POWER GND
J 1
(-4975 6225);
DISPLAY 0.872340 (-4975 6225);
PAINT GREEN (-4975 6225);
DISPLAY INVISIBLE (-4975 6225);
FORCEADD OFFPAGE..4
(-3050 900);
FORCEPROP 2 LAST $XR0 184 
J 0
(-2864 900);
DISPLAY 0.638298 (-2864 900);
PAINT MONO (-2864 900);
FORCEPROP 1 LAST OFFPAGE TRUE
J 0
(-2725 775);
DISPLAY 0.872340 (-2725 775);
PAINT GREEN (-2725 775);
DISPLAY INVISIBLE (-2725 775);
FORCEPROP 2 LAST PATH I155
J 0
(-2875 975);
DISPLAY 1.021277 (-2875 975);
DISPLAY INVISIBLE (-2875 975);
FORCEPROP 2 LAST CDS_LIB standard
J 0
(-3050 900);
DISPLAY INVISIBLE (-3050 900);
FORCEPROP 1 LAST COMMENT_BODY TRUE
J 0
(-3075 800);
DISPLAY 0.872340 (-3075 800);
PAINT GREEN (-3075 800);
DISPLAY INVISIBLE (-3075 800);
FORCEADD UNIVERSAL_GND..1
(-3325 5425);
FORCEPROP 3 LASTPIN (-3325 5475) SIG_NAME GND\g
J 0
(-3315 5485);
DISPLAY 0.659574 (-3315 5485);
PAINT MONO (-3315 5485);
DISPLAY INVISIBLE (-3315 5485);
FORCEPROP 2 LAST CDS_LIB pure_quanta_power
J 0
(-3325 5425);
DISPLAY INVISIBLE (-3325 5425);
FORCEPROP 1 LAST PATH I159
J 0
(-3250 5425);
DISPLAY 0.872340 (-3250 5425);
PAINT AQUA (-3250 5425);
DISPLAY INVISIBLE (-3250 5425);
FORCEPROP 1 LAST HDL_POWER GND
J 1
(-3300 5350);
DISPLAY 0.872340 (-3300 5350);
PAINT GREEN (-3300 5350);
DISPLAY INVISIBLE (-3300 5350);
FORCEADD Q_CAP..1
(-3325 5625);
FORCEPROP 1 LAST LOCATION PC9
J 0
(-3275 5725);
DISPLAY 0.489362 (-3275 5725);
PAINT SKYBLUE (-3275 5725);
FORCEPROP 0 LAST $SEC 1
J 0
(-3275 5750);
DISPLAY 0.680851 (-3275 5750);
PAINT MONO (-3275 5750);
DISPLAY INVISIBLE (-3275 5750);
FORCEPROP 0 LAST CDS_SEC 1
J 0
(-3275 5750);
DISPLAY 1.021277 (-3275 5750);
DISPLAY INVISIBLE (-3275 5750);
FORCEPROP 1 LASTPIN (-3325 5725) $PN 1
J 0
(-3315 5705);
DISPLAY 0.489362 (-3315 5705);
PAINT MONO (-3315 5705);
FORCEPROP 1 LASTPIN (-3325 5525) $PN 2
J 0
(-3315 5505);
DISPLAY 0.489362 (-3315 5505);
PAINT MONO (-3315 5505);
FORCEPROP 1 LAST PART_NUMBER CH4104K1B00
J 0
(-3275 5475);
DISPLAY 0.489362 (-3275 5475);
PAINT SKYBLUE (-3275 5475);
FORCEPROP 1 LAST MATERIAL X7R
J 0
(-3275 5525);
DISPLAY 0.489362 (-3275 5525);
PAINT SKYBLUE (-3275 5525);
FORCEPROP 1 LAST TOLERANCE 10%
J 0
(-3275 5575);
DISPLAY 0.489362 (-3275 5575);
PAINT SKYBLUE (-3275 5575);
FORCEPROP 1 LAST VALUE 0.1UF
J 0
(-3275 5675);
DISPLAY 0.489362 (-3275 5675);
PAINT SKYBLUE (-3275 5675);
FORCEPROP 1 LAST VOLTAGE 25V
J 0
(-3275 5625);
DISPLAY 0.489362 (-3275 5625);
PAINT SKYBLUE (-3275 5625);
FORCEPROP 1 LAST PACK_TYPE 0402
J 0
(-3275 5425);
DISPLAY 0.489362 (-3275 5425);
PAINT SKYBLUE (-3275 5425);
FORCEPROP 2 LAST CDS_LIB pure_quanta
J 0
(-3325 5625);
DISPLAY INVISIBLE (-3325 5625);
FORCEPROP 1 LAST PATH I160
J 0
(-3275 5775);
DISPLAY 0.978723 (-3275 5775);
PAINT WHITE (-3275 5775);
DISPLAY INVISIBLE (-3275 5775);
FORCEADD UNIVERSAL_GND..1
(-3325 5875);
FORCEPROP 3 LASTPIN (-3325 5925) SIG_NAME GND\g
J 0
(-3315 5935);
DISPLAY 0.659574 (-3315 5935);
PAINT MONO (-3315 5935);
DISPLAY INVISIBLE (-3315 5935);
FORCEPROP 2 LAST CDS_LIB pure_quanta_power
J 0
(-3325 5875);
DISPLAY INVISIBLE (-3325 5875);
FORCEPROP 1 LAST PATH I161
J 0
(-3250 5875);
DISPLAY 0.872340 (-3250 5875);
PAINT AQUA (-3250 5875);
DISPLAY INVISIBLE (-3250 5875);
FORCEPROP 1 LAST HDL_POWER GND
J 1
(-3300 5800);
DISPLAY 0.872340 (-3300 5800);
PAINT GREEN (-3300 5800);
DISPLAY INVISIBLE (-3300 5800);
FORCEADD Q_CAP..1
(-3325 6125);
FORCEPROP 1 LAST LOCATION PC4
J 0
(-3275 6225);
DISPLAY 0.489362 (-3275 6225);
PAINT SKYBLUE (-3275 6225);
FORCEPROP 0 LAST $SEC 1
J 0
(-3275 6250);
DISPLAY 0.680851 (-3275 6250);
PAINT MONO (-3275 6250);
DISPLAY INVISIBLE (-3275 6250);
FORCEPROP 0 LAST CDS_SEC 1
J 0
(-3275 6250);
DISPLAY 1.021277 (-3275 6250);
DISPLAY INVISIBLE (-3275 6250);
FORCEPROP 1 LASTPIN (-3325 6225) $PN 1
J 0
(-3315 6205);
DISPLAY 0.489362 (-3315 6205);
PAINT MONO (-3315 6205);
FORCEPROP 1 LASTPIN (-3325 6025) $PN 2
J 0
(-3315 6005);
DISPLAY 0.489362 (-3315 6005);
PAINT MONO (-3315 6005);
FORCEPROP 1 LAST MATERIAL X7R
J 0
(-3275 6025);
DISPLAY 0.489362 (-3275 6025);
PAINT SKYBLUE (-3275 6025);
FORCEPROP 1 LAST TOLERANCE 10%
J 0
(-3275 6075);
DISPLAY 0.489362 (-3275 6075);
PAINT SKYBLUE (-3275 6075);
FORCEPROP 1 LAST VALUE 0.1UF
J 0
(-3275 6175);
DISPLAY 0.489362 (-3275 6175);
PAINT SKYBLUE (-3275 6175);
FORCEPROP 1 LAST PART_NUMBER CH4104K1B00
J 0
(-3275 5975);
DISPLAY 0.489362 (-3275 5975);
PAINT SKYBLUE (-3275 5975);
FORCEPROP 1 LAST VOLTAGE 25V
J 0
(-3275 6125);
DISPLAY 0.489362 (-3275 6125);
PAINT SKYBLUE (-3275 6125);
FORCEPROP 1 LAST PACK_TYPE 0402
J 0
(-3275 5925);
DISPLAY 0.489362 (-3275 5925);
PAINT SKYBLUE (-3275 5925);
FORCEPROP 2 LAST CDS_LIB pure_quanta
J 0
(-3325 6125);
DISPLAY INVISIBLE (-3325 6125);
FORCEPROP 1 LAST PATH I162
J 0
(-3275 6275);
DISPLAY 0.978723 (-3275 6275);
PAINT WHITE (-3275 6275);
DISPLAY INVISIBLE (-3275 6275);
FORCEADD Q_RES..1
(-3050 1200);
FORCEPROP 1 LAST LOCATION PR412
J 0
(-3100 1250);
DISPLAY 0.489362 (-3100 1250);
PAINT SKYBLUE (-3100 1250);
FORCEPROP 0 LAST $SEC 1
J 0
(-3100 1275);
DISPLAY 0.680851 (-3100 1275);
PAINT MONO (-3100 1275);
DISPLAY INVISIBLE (-3100 1275);
FORCEPROP 0 LAST CDS_SEC 1
J 0
(-3100 1275);
DISPLAY 1.021277 (-3100 1275);
DISPLAY INVISIBLE (-3100 1275);
FORCEPROP 1 LASTPIN (-3150 1200) $PN 1
J 0
(-3138 1212);
DISPLAY 0.489362 (-3138 1212);
PAINT MONO (-3138 1212);
FORCEPROP 1 LASTPIN (-2950 1200) $PN 2
J 0
(-2988 1212);
DISPLAY 0.489362 (-2988 1212);
PAINT MONO (-2988 1212);
FORCEPROP 1 LAST WATTAGE 1/16W
J 2
(-3125 1150);
DISPLAY 0.489362 (-3125 1150);
PAINT SKYBLUE (-3125 1150);
FORCEPROP 1 LAST MATERIAL CHIP
J 0
(-3375 1150);
DISPLAY 0.489362 (-3375 1150);
PAINT SKYBLUE (-3375 1150);
FORCEPROP 1 LAST TOLERANCE 5%
J 0
(-3025 1150);
DISPLAY 0.489362 (-3025 1150);
PAINT SKYBLUE (-3025 1150);
FORCEPROP 1 LAST VALUE 0
J 2
(-3050 1150);
DISPLAY 0.489362 (-3050 1150);
PAINT SKYBLUE (-3050 1150);
FORCEPROP 1 LAST PART_NUMBER CS00002JB38
J 0
(-3725 1150);
DISPLAY 0.489362 (-3725 1150);
PAINT SKYBLUE (-3725 1150);
FORCEPROP 1 LAST PACK_TYPE 0402LF
J 0
(-2950 1150);
DISPLAY 0.489362 (-2950 1150);
PAINT SKYBLUE (-2950 1150);
FORCEPROP 2 LAST CDS_LIB pure_quanta
J 0
(-3050 1200);
DISPLAY INVISIBLE (-3050 1200);
FORCEPROP 1 LAST PATH I163
J 0
(-3100 1350);
DISPLAY 0.978723 (-3100 1350);
PAINT WHITE (-3100 1350);
DISPLAY INVISIBLE (-3100 1350);
FORCEADD UNIVERSAL_GND..1
(-2600 1125);
FORCEPROP 3 LASTPIN (-2600 1175) SIG_NAME GND\g
J 0
(-2590 1185);
DISPLAY 0.659574 (-2590 1185);
PAINT MONO (-2590 1185);
DISPLAY INVISIBLE (-2590 1185);
FORCEPROP 2 LAST CDS_LIB pure_quanta_power
J 0
(-2600 1125);
DISPLAY INVISIBLE (-2600 1125);
FORCEPROP 1 LAST PATH I165
J 0
(-2525 1125);
DISPLAY 0.872340 (-2525 1125);
PAINT AQUA (-2525 1125);
DISPLAY INVISIBLE (-2525 1125);
FORCEPROP 1 LAST HDL_POWER GND
J 1
(-2575 1050);
DISPLAY 0.872340 (-2575 1050);
PAINT GREEN (-2575 1050);
DISPLAY INVISIBLE (-2575 1050);
FORCEADD UNIVERSAL_GND..1
(-2075 1175);
FORCEPROP 3 LASTPIN (-2075 1225) SIG_NAME GND\g
J 0
(-2065 1235);
DISPLAY 0.659574 (-2065 1235);
PAINT MONO (-2065 1235);
DISPLAY INVISIBLE (-2065 1235);
FORCEPROP 2 LAST CDS_LIB pure_quanta_power
J 0
(-2075 1175);
DISPLAY INVISIBLE (-2075 1175);
FORCEPROP 1 LAST PATH I167
J 0
(-2000 1175);
DISPLAY 0.872340 (-2000 1175);
PAINT AQUA (-2000 1175);
DISPLAY INVISIBLE (-2000 1175);
FORCEPROP 1 LAST HDL_POWER GND
J 1
(-2050 1100);
DISPLAY 0.872340 (-2050 1100);
PAINT GREEN (-2050 1100);
DISPLAY INVISIBLE (-2050 1100);
FORCEADD Q_RES..2
(-2075 1400);
FORCEPROP 1 LAST LOCATION PR127
J 0
(-2030 1525);
DISPLAY 0.489362 (-2030 1525);
PAINT SKYBLUE (-2030 1525);
FORCEPROP 0 LAST $SEC 1
J 0
(-2025 1550);
DISPLAY 0.680851 (-2025 1550);
PAINT MONO (-2025 1550);
DISPLAY INVISIBLE (-2025 1550);
FORCEPROP 0 LAST CDS_SEC 1
J 0
(-2025 1550);
DISPLAY 1.021277 (-2025 1550);
DISPLAY INVISIBLE (-2025 1550);
FORCEPROP 1 LASTPIN (-2075 1500) $PN 1
J 0
(-2070 1462);
DISPLAY 0.489362 (-2070 1462);
PAINT MONO (-2070 1462);
FORCEPROP 1 LASTPIN (-2075 1300) $PN 2
J 0
(-2070 1310);
DISPLAY 0.489362 (-2070 1310);
PAINT MONO (-2070 1310);
FORCEPROP 1 LAST WATTAGE 1/16W
J 0
(-2035 1375);
DISPLAY 0.489362 (-2035 1375);
PAINT SKYBLUE (-2035 1375);
FORCEPROP 1 LAST MATERIAL EMPTY
J 0
(-2035 1325);
DISPLAY 0.489362 (-2035 1325);
PAINT RED (-2035 1325);
FORCEPROP 1 LAST TOLERANCE 5%
J 0
(-2030 1425);
DISPLAY 0.489362 (-2030 1425);
PAINT SKYBLUE (-2030 1425);
FORCEPROP 1 LAST VALUE 0
J 0
(-2030 1475);
DISPLAY 0.489362 (-2030 1475);
PAINT SKYBLUE (-2030 1475);
FORCEPROP 1 LAST PART_NUMBER CS00002JB38
J 0
(-2035 1275);
DISPLAY 0.489362 (-2035 1275);
PAINT SKYBLUE (-2035 1275);
FORCEPROP 1 LAST PACK_TYPE 0402LF
J 0
(-2035 1225);
DISPLAY 0.489362 (-2035 1225);
PAINT SKYBLUE (-2035 1225);
FORCEPROP 2 LAST CDS_LIB pure_quanta
J 0
(-2075 1400);
DISPLAY INVISIBLE (-2075 1400);
FORCEPROP 1 LAST PATH I168
J 0
(-2025 1575);
DISPLAY 0.978723 (-2025 1575);
PAINT WHITE (-2025 1575);
DISPLAY INVISIBLE (-2025 1575);
FORCEADD Q_RES..1
(-1600 1600);
FORCEPROP 1 LAST LOCATION PR129
J 0
(-1650 1650);
DISPLAY 0.489362 (-1650 1650);
PAINT SKYBLUE (-1650 1650);
FORCEPROP 0 LAST $SEC 1
J 0
(-1650 1675);
DISPLAY 0.680851 (-1650 1675);
PAINT MONO (-1650 1675);
DISPLAY INVISIBLE (-1650 1675);
FORCEPROP 0 LAST CDS_SEC 1
J 0
(-1650 1675);
DISPLAY 1.021277 (-1650 1675);
DISPLAY INVISIBLE (-1650 1675);
FORCEPROP 1 LASTPIN (-1700 1600) $PN 1
J 0
(-1688 1612);
DISPLAY 0.489362 (-1688 1612);
PAINT MONO (-1688 1612);
FORCEPROP 1 LASTPIN (-1500 1600) $PN 2
J 0
(-1538 1612);
DISPLAY 0.489362 (-1538 1612);
PAINT MONO (-1538 1612);
FORCEPROP 1 LAST WATTAGE 1/16W
J 0
(-1500 1550);
DISPLAY 0.489362 (-1500 1550);
PAINT SKYBLUE (-1500 1550);
FORCEPROP 1 LAST MATERIAL EMPTY
J 0
(-1850 1525);
DISPLAY 0.489362 (-1850 1525);
PAINT RED (-1850 1525);
FORCEPROP 1 LAST TOLERANCE 5%
J 0
(-1475 1625);
DISPLAY 0.489362 (-1475 1625);
PAINT SKYBLUE (-1475 1625);
FORCEPROP 1 LAST VALUE 0
J 2
(-1725 1625);
DISPLAY 0.489362 (-1725 1625);
PAINT SKYBLUE (-1725 1625);
FORCEPROP 1 LAST PART_NUMBER CS00002JB38
J 0
(-1850 1550);
DISPLAY 0.489362 (-1850 1550);
PAINT SKYBLUE (-1850 1550);
FORCEPROP 1 LAST PACK_TYPE 0402LF
J 0
(-1500 1525);
DISPLAY 0.489362 (-1500 1525);
PAINT SKYBLUE (-1500 1525);
FORCEPROP 2 LAST CDS_LIB pure_quanta
J 0
(-1600 1600);
DISPLAY INVISIBLE (-1600 1600);
FORCEPROP 1 LAST PATH I178
J 0
(-1650 1750);
DISPLAY 0.978723 (-1650 1750);
PAINT WHITE (-1650 1750);
DISPLAY INVISIBLE (-1650 1750);
FORCEADD Q_RES..1
(-1650 1825);
FORCEPROP 1 LAST LOCATION PR128
J 0
(-1700 1875);
DISPLAY 0.489362 (-1700 1875);
PAINT SKYBLUE (-1700 1875);
FORCEPROP 0 LAST $SEC 1
J 0
(-1700 1900);
DISPLAY 0.680851 (-1700 1900);
PAINT MONO (-1700 1900);
DISPLAY INVISIBLE (-1700 1900);
FORCEPROP 0 LAST CDS_SEC 1
J 0
(-1600 2000);
DISPLAY 1.021277 (-1600 2000);
DISPLAY INVISIBLE (-1600 2000);
FORCEPROP 1 LASTPIN (-1750 1825) $PN 1
J 0
(-1738 1837);
DISPLAY 0.489362 (-1738 1837);
PAINT MONO (-1738 1837);
FORCEPROP 1 LASTPIN (-1550 1825) $PN 2
J 0
(-1588 1837);
DISPLAY 0.489362 (-1588 1837);
PAINT MONO (-1588 1837);
FORCEPROP 1 LAST WATTAGE 1/16W
J 0
(-1475 1750);
DISPLAY 0.489362 (-1475 1750);
PAINT SKYBLUE (-1475 1750);
FORCEPROP 1 LAST MATERIAL EMPTY
J 0
(-1875 1750);
DISPLAY 0.489362 (-1875 1750);
PAINT RED (-1875 1750);
FORCEPROP 1 LAST TOLERANCE 1%
J 0
(-1525 1850);
DISPLAY 0.489362 (-1525 1850);
PAINT SKYBLUE (-1525 1850);
FORCEPROP 1 LAST VALUE 1K
J 2
(-1775 1850);
DISPLAY 0.489362 (-1775 1850);
PAINT SKYBLUE (-1775 1850);
FORCEPROP 1 LAST PART_NUMBER TMP_QCS21002FB24
J 0
(-1875 1775);
DISPLAY 0.489362 (-1875 1775);
PAINT SKYBLUE (-1875 1775);
FORCEPROP 1 LAST PACK_TYPE 0402LF
J 0
(-1475 1775);
DISPLAY 0.489362 (-1475 1775);
PAINT SKYBLUE (-1475 1775);
FORCEPROP 2 LAST CDS_LIB pure_quanta
J 0
(-1650 1825);
DISPLAY INVISIBLE (-1650 1825);
FORCEPROP 1 LAST PATH I179
J 0
(-1700 1975);
DISPLAY 0.978723 (-1700 1975);
PAINT WHITE (-1700 1975);
DISPLAY INVISIBLE (-1700 1975);
FORCEADD VCC_CORE..1
(-1300 1975);
FORCEPROP 3 LASTPIN (-1300 1925) SIG_NAME PVDD18_S5_P0\g
J 0
(-1290 1935);
DISPLAY 0.659574 (-1290 1935);
PAINT MONO (-1290 1935);
DISPLAY INVISIBLE (-1290 1935);
FORCEPROP 1 LAST HDL_POWER PVDD18_S5_P0
J 1
(-1300 2025);
DISPLAY 0.489362 (-1300 2025);
PAINT GREEN (-1300 2025);
FORCEPROP 2 LAST CDS_LIB pure_quanta_power
J 0
(-1300 1975);
DISPLAY INVISIBLE (-1300 1975);
FORCEPROP 1 LAST PATH I180
J 0
(-1250 2000);
DISPLAY 0.872340 (-1250 2000);
PAINT AQUA (-1250 2000);
DISPLAY INVISIBLE (-1250 2000);
FORCEADD OFFPAGE..4
(-750 1600);
FORCEPROP 2 LAST $XR0 80 
J 0
(-564 1600);
DISPLAY 0.638298 (-564 1600);
PAINT MONO (-564 1600);
FORCEPROP 1 LAST OFFPAGE TRUE
J 0
(-425 1475);
DISPLAY 0.872340 (-425 1475);
PAINT GREEN (-425 1475);
DISPLAY INVISIBLE (-425 1475);
FORCEPROP 2 LAST PATH I181
J 0
(-575 1675);
DISPLAY 1.021277 (-575 1675);
DISPLAY INVISIBLE (-575 1675);
FORCEPROP 2 LAST CDS_LIB standard
J 2
(-750 1600);
DISPLAY INVISIBLE (-750 1600);
FORCEPROP 1 LAST COMMENT_BODY TRUE
J 0
(-775 1500);
DISPLAY 0.872340 (-775 1500);
PAINT GREEN (-775 1500);
DISPLAY INVISIBLE (-775 1500);
FORCEADD UNIVERSAL_GND..1
(-5975 5100);
FORCEPROP 3 LASTPIN (-5975 5150) SIG_NAME GND\g
J 0
(-5965 5160);
DISPLAY 0.659574 (-5965 5160);
PAINT MONO (-5965 5160);
DISPLAY INVISIBLE (-5965 5160);
FORCEPROP 2 LAST CDS_LIB pure_quanta_power
J 0
(-5975 5100);
DISPLAY INVISIBLE (-5975 5100);
FORCEPROP 1 LAST PATH I188
J 0
(-5900 5100);
DISPLAY 0.872340 (-5900 5100);
PAINT AQUA (-5900 5100);
DISPLAY INVISIBLE (-5900 5100);
FORCEPROP 1 LAST HDL_POWER GND
J 1
(-5950 5025);
DISPLAY 0.872340 (-5950 5025);
PAINT GREEN (-5950 5025);
DISPLAY INVISIBLE (-5950 5025);
FORCEADD Q_RES..1
(-6100 1700);
FORCEPROP 1 LAST LOCATION PR458
J 0
(-6150 1750);
DISPLAY 0.489362 (-6150 1750);
PAINT SKYBLUE (-6150 1750);
FORCEPROP 0 LAST $SEC 1
J 0
(-6150 1775);
DISPLAY 0.680851 (-6150 1775);
PAINT MONO (-6150 1775);
DISPLAY INVISIBLE (-6150 1775);
FORCEPROP 0 LAST CDS_SEC 1
J 0
(-6150 1775);
DISPLAY 1.021277 (-6150 1775);
DISPLAY INVISIBLE (-6150 1775);
FORCEPROP 1 LASTPIN (-6200 1700) $PN 1
J 0
(-6188 1712);
DISPLAY 0.489362 (-6188 1712);
PAINT MONO (-6188 1712);
FORCEPROP 1 LASTPIN (-6000 1700) $PN 2
J 0
(-6038 1712);
DISPLAY 0.489362 (-6038 1712);
PAINT MONO (-6038 1712);
FORCEPROP 1 LAST WATTAGE 1/16W
J 0
(-6000 1650);
DISPLAY 0.489362 (-6000 1650);
PAINT SKYBLUE (-6000 1650);
FORCEPROP 1 LAST MATERIAL EMPTY
J 0
(-6350 1625);
DISPLAY 0.489362 (-6350 1625);
PAINT RED (-6350 1625);
FORCEPROP 1 LAST TOLERANCE 5%
J 0
(-5975 1725);
DISPLAY 0.489362 (-5975 1725);
PAINT SKYBLUE (-5975 1725);
FORCEPROP 1 LAST VALUE 0
J 2
(-6225 1725);
DISPLAY 0.489362 (-6225 1725);
PAINT SKYBLUE (-6225 1725);
FORCEPROP 1 LAST PART_NUMBER CS00002JB38
J 0
(-6350 1650);
DISPLAY 0.489362 (-6350 1650);
PAINT SKYBLUE (-6350 1650);
FORCEPROP 1 LAST PACK_TYPE 0402LF
J 0
(-6000 1625);
DISPLAY 0.489362 (-6000 1625);
PAINT SKYBLUE (-6000 1625);
FORCEPROP 2 LAST CDS_LIB pure_quanta
J 0
(-6100 1700);
DISPLAY INVISIBLE (-6100 1700);
FORCEPROP 1 LAST PATH I189
J 0
(-6150 1850);
DISPLAY 0.978723 (-6150 1850);
PAINT WHITE (-6150 1850);
DISPLAY INVISIBLE (-6150 1850);
FORCEADD VCC_CORE..1
(-6525 1825);
FORCEPROP 3 LASTPIN (-6525 1775) SIG_NAME P3V3_STBY\g
J 0
(-6515 1785);
DISPLAY 0.659574 (-6515 1785);
PAINT MONO (-6515 1785);
DISPLAY INVISIBLE (-6515 1785);
FORCEPROP 1 LAST HDL_POWER P3V3_STBY
J 1
(-6525 1875);
DISPLAY 0.489362 (-6525 1875);
PAINT GREEN (-6525 1875);
FORCEPROP 2 LAST CDS_LIB pure_quanta_power
J 0
(-6525 1825);
DISPLAY INVISIBLE (-6525 1825);
FORCEPROP 1 LAST PATH I190
J 0
(-6475 1850);
DISPLAY 0.872340 (-6475 1850);
PAINT AQUA (-6475 1850);
DISPLAY INVISIBLE (-6475 1850);
FORCEADD Q_RES..1
(-3050 2300);
FORCEPROP 1 LAST LOCATION PR419
J 0
(-3100 2350);
DISPLAY 0.489362 (-3100 2350);
PAINT SKYBLUE (-3100 2350);
FORCEPROP 0 LAST $SEC 1
J 0
(-3100 2375);
DISPLAY 0.680851 (-3100 2375);
PAINT MONO (-3100 2375);
DISPLAY INVISIBLE (-3100 2375);
FORCEPROP 0 LAST CDS_SEC 1
J 0
(-3100 2375);
DISPLAY 1.021277 (-3100 2375);
DISPLAY INVISIBLE (-3100 2375);
FORCEPROP 1 LASTPIN (-3150 2300) $PN 1
J 0
(-3138 2312);
DISPLAY 0.489362 (-3138 2312);
PAINT MONO (-3138 2312);
FORCEPROP 1 LASTPIN (-2950 2300) $PN 2
J 0
(-2988 2312);
DISPLAY 0.489362 (-2988 2312);
PAINT MONO (-2988 2312);
FORCEPROP 1 LAST WATTAGE 1/16W
J 2
(-3125 2250);
DISPLAY 0.489362 (-3125 2250);
PAINT SKYBLUE (-3125 2250);
FORCEPROP 1 LAST MATERIAL CHIP
J 0
(-3375 2250);
DISPLAY 0.489362 (-3375 2250);
PAINT SKYBLUE (-3375 2250);
FORCEPROP 1 LAST TOLERANCE 5%
J 0
(-3025 2250);
DISPLAY 0.489362 (-3025 2250);
PAINT SKYBLUE (-3025 2250);
FORCEPROP 1 LAST VALUE 0
J 2
(-3050 2250);
DISPLAY 0.489362 (-3050 2250);
PAINT SKYBLUE (-3050 2250);
FORCEPROP 1 LAST PACK_TYPE 0402LF
J 0
(-2950 2250);
DISPLAY 0.489362 (-2950 2250);
PAINT SKYBLUE (-2950 2250);
FORCEPROP 1 LAST PART_NUMBER CS00002JB38
J 0
(-3725 2250);
DISPLAY 0.489362 (-3725 2250);
PAINT SKYBLUE (-3725 2250);
FORCEPROP 2 LAST CDS_LIB pure_quanta
J 0
(-3050 2300);
DISPLAY INVISIBLE (-3050 2300);
FORCEPROP 1 LAST PATH I211
J 0
(-3100 2450);
DISPLAY 0.978723 (-3100 2450);
PAINT WHITE (-3100 2450);
DISPLAY INVISIBLE (-3100 2450);
FORCEADD UNIVERSAL_GND..1
(-2600 4025);
FORCEPROP 3 LASTPIN (-2600 4075) SIG_NAME GND\g
J 0
(-2590 4085);
DISPLAY 0.659574 (-2590 4085);
PAINT MONO (-2590 4085);
DISPLAY INVISIBLE (-2590 4085);
FORCEPROP 2 LAST CDS_LIB pure_quanta_power
J 0
(-2600 4025);
DISPLAY INVISIBLE (-2600 4025);
FORCEPROP 1 LAST PATH I212
J 0
(-2525 4025);
DISPLAY 0.872340 (-2525 4025);
PAINT AQUA (-2525 4025);
DISPLAY INVISIBLE (-2525 4025);
FORCEPROP 1 LAST HDL_POWER GND
J 1
(-2575 3950);
DISPLAY 0.872340 (-2575 3950);
PAINT GREEN (-2575 3950);
DISPLAY INVISIBLE (-2575 3950);
FORCEADD UNIVERSAL_GND..1
(-2600 3575);
FORCEPROP 3 LASTPIN (-2600 3625) SIG_NAME GND\g
J 0
(-2590 3635);
DISPLAY 0.659574 (-2590 3635);
PAINT MONO (-2590 3635);
DISPLAY INVISIBLE (-2590 3635);
FORCEPROP 2 LAST CDS_LIB pure_quanta_power
J 0
(-2600 3575);
DISPLAY INVISIBLE (-2600 3575);
FORCEPROP 1 LAST PATH I213
J 0
(-2525 3575);
DISPLAY 0.872340 (-2525 3575);
PAINT AQUA (-2525 3575);
DISPLAY INVISIBLE (-2525 3575);
FORCEPROP 1 LAST HDL_POWER GND
J 1
(-2575 3500);
DISPLAY 0.872340 (-2575 3500);
PAINT GREEN (-2575 3500);
DISPLAY INVISIBLE (-2575 3500);
FORCEADD Q_RES..1
(-3025 4100);
FORCEPROP 1 LAST LOCATION PR37
J 0
(-3075 4150);
DISPLAY 0.489362 (-3075 4150);
PAINT SKYBLUE (-3075 4150);
FORCEPROP 0 LAST $SEC 1
J 0
(-3075 4200);
DISPLAY 0.680851 (-3075 4200);
PAINT MONO (-3075 4200);
DISPLAY INVISIBLE (-3075 4200);
FORCEPROP 0 LAST CDS_SEC 1
J 0
(-3075 4200);
DISPLAY 1.021277 (-3075 4200);
DISPLAY INVISIBLE (-3075 4200);
FORCEPROP 1 LASTPIN (-3125 4100) $PN 1
J 0
(-3113 4112);
DISPLAY 0.489362 (-3113 4112);
PAINT MONO (-3113 4112);
FORCEPROP 1 LASTPIN (-2925 4100) $PN 2
J 0
(-2963 4112);
DISPLAY 0.489362 (-2963 4112);
PAINT MONO (-2963 4112);
FORCEPROP 1 LAST WATTAGE 1/16W
J 2
(-3100 4050);
DISPLAY 0.489362 (-3100 4050);
PAINT SKYBLUE (-3100 4050);
FORCEPROP 1 LAST MATERIAL CHIP
J 0
(-3350 4050);
DISPLAY 0.489362 (-3350 4050);
PAINT SKYBLUE (-3350 4050);
FORCEPROP 1 LAST PART_NUMBER CS00002JB38
J 0
(-3700 4050);
DISPLAY 0.489362 (-3700 4050);
PAINT SKYBLUE (-3700 4050);
FORCEPROP 1 LAST TOLERANCE 5%
J 0
(-3000 4050);
DISPLAY 0.489362 (-3000 4050);
PAINT SKYBLUE (-3000 4050);
FORCEPROP 1 LAST VALUE 0
J 2
(-3025 4050);
DISPLAY 0.489362 (-3025 4050);
PAINT SKYBLUE (-3025 4050);
FORCEPROP 1 LAST PACK_TYPE 0402LF
J 0
(-2925 4050);
DISPLAY 0.489362 (-2925 4050);
PAINT SKYBLUE (-2925 4050);
FORCEPROP 2 LAST CDS_LIB pure_quanta
J 0
(-3025 4100);
DISPLAY INVISIBLE (-3025 4100);
FORCEPROP 1 LAST PATH I214
J 0
(-3075 4250);
DISPLAY 0.978723 (-3075 4250);
PAINT WHITE (-3075 4250);
DISPLAY INVISIBLE (-3075 4250);
FORCEADD Q_RES..1
(-3050 3650);
FORCEPROP 1 LAST LOCATION PR33
J 0
(-3100 3700);
DISPLAY 0.489362 (-3100 3700);
PAINT SKYBLUE (-3100 3700);
FORCEPROP 0 LAST $SEC 1
J 0
(-3100 3750);
DISPLAY 0.680851 (-3100 3750);
PAINT MONO (-3100 3750);
DISPLAY INVISIBLE (-3100 3750);
FORCEPROP 0 LAST CDS_SEC 1
J 0
(-3100 3750);
DISPLAY 1.021277 (-3100 3750);
DISPLAY INVISIBLE (-3100 3750);
FORCEPROP 1 LASTPIN (-3150 3650) $PN 1
J 0
(-3138 3662);
DISPLAY 0.489362 (-3138 3662);
PAINT MONO (-3138 3662);
FORCEPROP 1 LASTPIN (-2950 3650) $PN 2
J 0
(-2988 3662);
DISPLAY 0.489362 (-2988 3662);
PAINT MONO (-2988 3662);
FORCEPROP 1 LAST WATTAGE 1/16W
J 2
(-3125 3600);
DISPLAY 0.489362 (-3125 3600);
PAINT SKYBLUE (-3125 3600);
FORCEPROP 1 LAST MATERIAL CHIP
J 0
(-3375 3600);
DISPLAY 0.489362 (-3375 3600);
PAINT SKYBLUE (-3375 3600);
FORCEPROP 1 LAST TOLERANCE 5%
J 0
(-3025 3600);
DISPLAY 0.489362 (-3025 3600);
PAINT SKYBLUE (-3025 3600);
FORCEPROP 1 LAST VALUE 0
J 2
(-3050 3600);
DISPLAY 0.489362 (-3050 3600);
PAINT SKYBLUE (-3050 3600);
FORCEPROP 1 LAST PART_NUMBER CS00002JB38
J 0
(-3725 3600);
DISPLAY 0.489362 (-3725 3600);
PAINT SKYBLUE (-3725 3600);
FORCEPROP 1 LAST PACK_TYPE 0402LF
J 0
(-2950 3600);
DISPLAY 0.489362 (-2950 3600);
PAINT SKYBLUE (-2950 3600);
FORCEPROP 2 LAST CDS_LIB pure_quanta
J 0
(-3050 3650);
DISPLAY INVISIBLE (-3050 3650);
FORCEPROP 1 LAST PATH I215
J 0
(-3100 3800);
DISPLAY 0.978723 (-3100 3800);
PAINT WHITE (-3100 3800);
DISPLAY INVISIBLE (-3100 3800);
FORCEADD Q_RES..1
(-3050 3200);
FORCEPROP 1 LAST LOCATION PR34
J 0
(-3100 3250);
DISPLAY 0.489362 (-3100 3250);
PAINT SKYBLUE (-3100 3250);
FORCEPROP 0 LAST $SEC 1
J 0
(-3100 3300);
DISPLAY 0.680851 (-3100 3300);
PAINT MONO (-3100 3300);
DISPLAY INVISIBLE (-3100 3300);
FORCEPROP 0 LAST CDS_SEC 1
J 0
(-3100 3300);
DISPLAY 1.021277 (-3100 3300);
DISPLAY INVISIBLE (-3100 3300);
FORCEPROP 1 LASTPIN (-3150 3200) $PN 1
J 0
(-3138 3212);
DISPLAY 0.489362 (-3138 3212);
PAINT MONO (-3138 3212);
FORCEPROP 1 LASTPIN (-2950 3200) $PN 2
J 0
(-2988 3212);
DISPLAY 0.489362 (-2988 3212);
PAINT MONO (-2988 3212);
FORCEPROP 1 LAST WATTAGE 1/16W
J 2
(-3125 3150);
DISPLAY 0.489362 (-3125 3150);
PAINT SKYBLUE (-3125 3150);
FORCEPROP 1 LAST MATERIAL CHIP
J 0
(-3375 3150);
DISPLAY 0.489362 (-3375 3150);
PAINT SKYBLUE (-3375 3150);
FORCEPROP 1 LAST TOLERANCE 5%
J 0
(-3025 3150);
DISPLAY 0.489362 (-3025 3150);
PAINT SKYBLUE (-3025 3150);
FORCEPROP 1 LAST VALUE 0
J 2
(-3050 3150);
DISPLAY 0.489362 (-3050 3150);
PAINT SKYBLUE (-3050 3150);
FORCEPROP 1 LAST PART_NUMBER CS00002JB38
J 0
(-3725 3150);
DISPLAY 0.489362 (-3725 3150);
PAINT SKYBLUE (-3725 3150);
FORCEPROP 1 LAST PACK_TYPE 0402LF
J 0
(-2950 3150);
DISPLAY 0.489362 (-2950 3150);
PAINT SKYBLUE (-2950 3150);
FORCEPROP 2 LAST CDS_LIB pure_quanta
J 0
(-3050 3200);
DISPLAY INVISIBLE (-3050 3200);
FORCEPROP 1 LAST PATH I216
J 0
(-3100 3350);
DISPLAY 0.978723 (-3100 3350);
PAINT WHITE (-3100 3350);
DISPLAY INVISIBLE (-3100 3350);
FORCEADD UNIVERSAL_GND..1
(-2600 3125);
FORCEPROP 3 LASTPIN (-2600 3175) SIG_NAME GND\g
J 0
(-2590 3185);
DISPLAY 0.659574 (-2590 3185);
PAINT MONO (-2590 3185);
DISPLAY INVISIBLE (-2590 3185);
FORCEPROP 2 LAST CDS_LIB pure_quanta_power
J 0
(-2600 3125);
DISPLAY INVISIBLE (-2600 3125);
FORCEPROP 1 LAST PATH I217
J 0
(-2525 3125);
DISPLAY 0.872340 (-2525 3125);
PAINT AQUA (-2525 3125);
DISPLAY INVISIBLE (-2525 3125);
FORCEPROP 1 LAST HDL_POWER GND
J 1
(-2575 3050);
DISPLAY 0.872340 (-2575 3050);
PAINT GREEN (-2575 3050);
DISPLAY INVISIBLE (-2575 3050);
FORCEADD UNIVERSAL_GND..1
(-2600 2675);
FORCEPROP 3 LASTPIN (-2600 2725) SIG_NAME GND\g
J 0
(-2590 2735);
DISPLAY 0.659574 (-2590 2735);
PAINT MONO (-2590 2735);
DISPLAY INVISIBLE (-2590 2735);
FORCEPROP 2 LAST CDS_LIB pure_quanta_power
J 0
(-2600 2675);
DISPLAY INVISIBLE (-2600 2675);
FORCEPROP 1 LAST PATH I218
J 0
(-2525 2675);
DISPLAY 0.872340 (-2525 2675);
PAINT AQUA (-2525 2675);
DISPLAY INVISIBLE (-2525 2675);
FORCEPROP 1 LAST HDL_POWER GND
J 1
(-2575 2600);
DISPLAY 0.872340 (-2575 2600);
PAINT GREEN (-2575 2600);
DISPLAY INVISIBLE (-2575 2600);
FORCEADD UNIVERSAL_GND..1
(-2600 2225);
FORCEPROP 3 LASTPIN (-2600 2275) SIG_NAME GND\g
J 0
(-2590 2285);
DISPLAY 0.659574 (-2590 2285);
PAINT MONO (-2590 2285);
DISPLAY INVISIBLE (-2590 2285);
FORCEPROP 2 LAST CDS_LIB pure_quanta_power
J 0
(-2600 2225);
DISPLAY INVISIBLE (-2600 2225);
FORCEPROP 1 LAST PATH I219
J 0
(-2525 2225);
DISPLAY 0.872340 (-2525 2225);
PAINT AQUA (-2525 2225);
DISPLAY INVISIBLE (-2525 2225);
FORCEPROP 1 LAST HDL_POWER GND
J 1
(-2575 2150);
DISPLAY 0.872340 (-2575 2150);
PAINT GREEN (-2575 2150);
DISPLAY INVISIBLE (-2575 2150);
FORCEADD UNIVERSAL_GND..1
(-2600 1775);
FORCEPROP 3 LASTPIN (-2600 1825) SIG_NAME GND\g
J 0
(-2590 1835);
DISPLAY 0.659574 (-2590 1835);
PAINT MONO (-2590 1835);
DISPLAY INVISIBLE (-2590 1835);
FORCEPROP 2 LAST CDS_LIB pure_quanta_power
J 0
(-2600 1775);
DISPLAY INVISIBLE (-2600 1775);
FORCEPROP 1 LAST PATH I220
J 0
(-2525 1775);
DISPLAY 0.872340 (-2525 1775);
PAINT AQUA (-2525 1775);
DISPLAY INVISIBLE (-2525 1775);
FORCEPROP 1 LAST HDL_POWER GND
J 1
(-2575 1700);
DISPLAY 0.872340 (-2575 1700);
PAINT GREEN (-2575 1700);
DISPLAY INVISIBLE (-2575 1700);
FORCEADD Q_RES..1
(-3050 2750);
FORCEPROP 1 LAST LOCATION PR35
J 0
(-3100 2800);
DISPLAY 0.489362 (-3100 2800);
PAINT SKYBLUE (-3100 2800);
FORCEPROP 0 LAST $SEC 1
J 0
(-3100 2850);
DISPLAY 0.680851 (-3100 2850);
PAINT MONO (-3100 2850);
DISPLAY INVISIBLE (-3100 2850);
FORCEPROP 0 LAST CDS_SEC 1
J 0
(-3100 2850);
DISPLAY 1.021277 (-3100 2850);
DISPLAY INVISIBLE (-3100 2850);
FORCEPROP 1 LASTPIN (-3150 2750) $PN 1
J 0
(-3138 2762);
DISPLAY 0.489362 (-3138 2762);
PAINT MONO (-3138 2762);
FORCEPROP 1 LASTPIN (-2950 2750) $PN 2
J 0
(-2988 2762);
DISPLAY 0.489362 (-2988 2762);
PAINT MONO (-2988 2762);
FORCEPROP 1 LAST PACK_TYPE 0402LF
J 0
(-2950 2700);
DISPLAY 0.489362 (-2950 2700);
PAINT SKYBLUE (-2950 2700);
FORCEPROP 1 LAST WATTAGE 1/16W
J 2
(-3125 2700);
DISPLAY 0.489362 (-3125 2700);
PAINT SKYBLUE (-3125 2700);
FORCEPROP 1 LAST MATERIAL CHIP
J 0
(-3375 2700);
DISPLAY 0.489362 (-3375 2700);
PAINT SKYBLUE (-3375 2700);
FORCEPROP 1 LAST TOLERANCE 5%
J 0
(-3025 2700);
DISPLAY 0.489362 (-3025 2700);
PAINT SKYBLUE (-3025 2700);
FORCEPROP 1 LAST VALUE 0
J 2
(-3050 2700);
DISPLAY 0.489362 (-3050 2700);
PAINT SKYBLUE (-3050 2700);
FORCEPROP 1 LAST PART_NUMBER CS00002JB38
J 0
(-3725 2700);
DISPLAY 0.489362 (-3725 2700);
PAINT SKYBLUE (-3725 2700);
FORCEPROP 2 LAST CDS_LIB pure_quanta
J 0
(-3050 2750);
DISPLAY INVISIBLE (-3050 2750);
FORCEPROP 1 LAST PATH I221
J 0
(-3100 2900);
DISPLAY 0.978723 (-3100 2900);
PAINT WHITE (-3100 2900);
DISPLAY INVISIBLE (-3100 2900);
FORCEADD Q_RES..1
(-3050 1850);
FORCEPROP 1 LAST LOCATION PR36
J 0
(-3100 1900);
DISPLAY 0.489362 (-3100 1900);
PAINT SKYBLUE (-3100 1900);
FORCEPROP 0 LAST $SEC 1
J 0
(-3100 1950);
DISPLAY 0.680851 (-3100 1950);
PAINT MONO (-3100 1950);
DISPLAY INVISIBLE (-3100 1950);
FORCEPROP 0 LAST CDS_SEC 1
J 0
(-3100 1950);
DISPLAY 1.021277 (-3100 1950);
DISPLAY INVISIBLE (-3100 1950);
FORCEPROP 1 LASTPIN (-3150 1850) $PN 1
J 0
(-3138 1862);
DISPLAY 0.489362 (-3138 1862);
PAINT MONO (-3138 1862);
FORCEPROP 1 LASTPIN (-2950 1850) $PN 2
J 0
(-2988 1862);
DISPLAY 0.489362 (-2988 1862);
PAINT MONO (-2988 1862);
FORCEPROP 1 LAST WATTAGE 1/16W
J 2
(-3125 1800);
DISPLAY 0.489362 (-3125 1800);
PAINT SKYBLUE (-3125 1800);
FORCEPROP 1 LAST MATERIAL CHIP
J 0
(-3375 1800);
DISPLAY 0.489362 (-3375 1800);
PAINT SKYBLUE (-3375 1800);
FORCEPROP 1 LAST TOLERANCE 5%
J 0
(-3025 1800);
DISPLAY 0.489362 (-3025 1800);
PAINT SKYBLUE (-3025 1800);
FORCEPROP 1 LAST VALUE 0
J 2
(-3050 1800);
DISPLAY 0.489362 (-3050 1800);
PAINT SKYBLUE (-3050 1800);
FORCEPROP 1 LAST PART_NUMBER CS00002JB38
J 0
(-3725 1800);
DISPLAY 0.489362 (-3725 1800);
PAINT SKYBLUE (-3725 1800);
FORCEPROP 1 LAST PACK_TYPE 0402LF
J 0
(-2950 1800);
DISPLAY 0.489362 (-2950 1800);
PAINT SKYBLUE (-2950 1800);
FORCEPROP 2 LAST CDS_LIB pure_quanta
J 0
(-3050 1850);
DISPLAY INVISIBLE (-3050 1850);
FORCEPROP 1 LAST PATH I222
J 0
(-3100 2000);
DISPLAY 0.978723 (-3100 2000);
PAINT WHITE (-3100 2000);
DISPLAY INVISIBLE (-3100 2000);
FORCEADD OFFPAGE..2
(-3025 5100);
FORCEPROP 2 LAST $XR0 184 
J 0
(-2836 5100);
DISPLAY 0.638298 (-2836 5100);
PAINT MONO (-2836 5100);
FORCEPROP 2 LAST PATH I223
J 0
(-2825 5150);
DISPLAY 1.021277 (-2825 5150);
DISPLAY INVISIBLE (-2825 5150);
FORCEPROP 1 LAST COMMENT_BODY TRUE
J 0
(-3070 5005);
DISPLAY 0.872340 (-3070 5005);
PAINT GREEN (-3070 5005);
DISPLAY INVISIBLE (-3070 5005);
FORCEPROP 1 LAST OFFPAGE TRUE
J 0
(-2700 4975);
DISPLAY 0.872340 (-2700 4975);
PAINT GREEN (-2700 4975);
DISPLAY INVISIBLE (-2700 4975);
FORCEPROP 2 LAST CDS_LIB standard
J 0
(-3025 5100);
DISPLAY INVISIBLE (-3025 5100);
FORCEADD OFFPAGE..4
(-3025 5000);
FORCEPROP 2 LAST $XR0 184 
J 0
(-2839 5000);
DISPLAY 0.638298 (-2839 5000);
PAINT MONO (-2839 5000);
FORCEPROP 2 LAST PATH I224
J 0
(-2825 5050);
DISPLAY 1.021277 (-2825 5050);
DISPLAY INVISIBLE (-2825 5050);
FORCEPROP 1 LAST COMMENT_BODY TRUE
J 0
(-3050 4900);
DISPLAY 0.872340 (-3050 4900);
PAINT GREEN (-3050 4900);
DISPLAY INVISIBLE (-3050 4900);
FORCEPROP 2 LAST CDS_LIB standard
J 0
(-3025 5000);
DISPLAY INVISIBLE (-3025 5000);
FORCEPROP 1 LAST OFFPAGE TRUE
J 0
(-2700 4875);
DISPLAY 0.872340 (-2700 4875);
PAINT GREEN (-2700 4875);
DISPLAY INVISIBLE (-2700 4875);
FORCEADD OFFPAGE..4
(-3025 4550);
FORCEPROP 2 LAST $XR0 184 
J 0
(-2839 4550);
DISPLAY 0.638298 (-2839 4550);
PAINT MONO (-2839 4550);
FORCEPROP 2 LAST PATH I225
J 0
(-2825 4600);
DISPLAY 1.021277 (-2825 4600);
DISPLAY INVISIBLE (-2825 4600);
FORCEPROP 1 LAST COMMENT_BODY TRUE
J 0
(-3050 4450);
DISPLAY 0.872340 (-3050 4450);
PAINT GREEN (-3050 4450);
DISPLAY INVISIBLE (-3050 4450);
FORCEPROP 2 LAST CDS_LIB standard
J 0
(-3025 4550);
DISPLAY INVISIBLE (-3025 4550);
FORCEPROP 1 LAST OFFPAGE TRUE
J 0
(-2700 4425);
DISPLAY 0.872340 (-2700 4425);
PAINT GREEN (-2700 4425);
DISPLAY INVISIBLE (-2700 4425);
FORCEADD OFFPAGE..2
(-3025 4650);
FORCEPROP 2 LAST $XR0 184 
J 0
(-2836 4650);
DISPLAY 0.638298 (-2836 4650);
PAINT MONO (-2836 4650);
FORCEPROP 2 LAST PATH I226
J 0
(-2825 4700);
DISPLAY 1.021277 (-2825 4700);
DISPLAY INVISIBLE (-2825 4700);
FORCEPROP 1 LAST COMMENT_BODY TRUE
J 0
(-3070 4555);
DISPLAY 0.872340 (-3070 4555);
PAINT GREEN (-3070 4555);
DISPLAY INVISIBLE (-3070 4555);
FORCEPROP 1 LAST OFFPAGE TRUE
J 0
(-2700 4525);
DISPLAY 0.872340 (-2700 4525);
PAINT GREEN (-2700 4525);
DISPLAY INVISIBLE (-2700 4525);
FORCEPROP 2 LAST CDS_LIB standard
J 0
(-3025 4650);
DISPLAY INVISIBLE (-3025 4650);
FORCEADD Q_RES..2
(-5625 450);
FORCEPROP 1 LAST LOCATION PR601
J 0
(-5575 575);
DISPLAY 0.489362 (-5575 575);
PAINT SKYBLUE (-5575 575);
FORCEPROP 0 LAST $SEC 1
J 0
(-5575 600);
DISPLAY 0.680851 (-5575 600);
PAINT MONO (-5575 600);
DISPLAY INVISIBLE (-5575 600);
FORCEPROP 0 LAST CDS_SEC 1
J 0
(-5575 600);
DISPLAY 0.680851 (-5575 600);
DISPLAY INVISIBLE (-5575 600);
FORCEPROP 1 LASTPIN (-5625 550) $PN 1
J 0
(-5620 512);
DISPLAY 0.787234 (-5620 512);
PAINT MONO (-5620 512);
DISPLAY INVISIBLE (-5620 512);
FORCEPROP 1 LASTPIN (-5625 350) $PN 2
J 0
(-5620 360);
DISPLAY 0.787234 (-5620 360);
PAINT MONO (-5620 360);
DISPLAY INVISIBLE (-5620 360);
FORCEPROP 1 LAST WATTAGE 1/16W
J 0
(-5575 425);
DISPLAY 0.489362 (-5575 425);
PAINT SKYBLUE (-5575 425);
FORCEPROP 1 LAST MATERIAL EMPTY
J 0
(-5575 375);
DISPLAY 0.489362 (-5575 375);
PAINT RED (-5575 375);
FORCEPROP 1 LAST TOLERANCE 1%
J 0
(-5575 475);
DISPLAY 0.489362 (-5575 475);
PAINT SKYBLUE (-5575 475);
FORCEPROP 1 LAST VALUE 4.99K
J 0
(-5575 525);
DISPLAY 0.489362 (-5575 525);
PAINT SKYBLUE (-5575 525);
FORCEPROP 1 LAST PART_NUMBER CS24992FB07
J 0
(-5575 325);
DISPLAY 0.489362 (-5575 325);
PAINT SKYBLUE (-5575 325);
FORCEPROP 1 LAST PACK_TYPE 0402LF
J 0
(-5575 275);
DISPLAY 0.489362 (-5575 275);
PAINT SKYBLUE (-5575 275);
FORCEPROP 2 LAST CDS_LIB pure_quanta
J 0
(-5625 450);
DISPLAY INVISIBLE (-5625 450);
FORCEPROP 1 LAST PATH I227
J 0
(-5575 625);
DISPLAY 0.978723 (-5575 625);
PAINT WHITE (-5575 625);
DISPLAY INVISIBLE (-5575 625);
FORCEADD UNIVERSAL_GND..1
(-5625 250);
FORCEPROP 3 LASTPIN (-5625 300) SIG_NAME GND\g
J 0
(-5615 310);
DISPLAY 0.659574 (-5615 310);
PAINT MONO (-5615 310);
DISPLAY INVISIBLE (-5615 310);
FORCEPROP 2 LAST CDS_LIB pure_quanta_power
J 0
(-5625 250);
DISPLAY INVISIBLE (-5625 250);
FORCEPROP 1 LAST PATH I228
J 0
(-5550 250);
DISPLAY 0.872340 (-5550 250);
PAINT AQUA (-5550 250);
DISPLAY INVISIBLE (-5550 250);
FORCEPROP 1 LAST HDL_POWER GND
J 1
(-5600 175);
DISPLAY 0.872340 (-5600 175);
PAINT GREEN (-5600 175);
DISPLAY INVISIBLE (-5600 175);
FORCEADD VCC_CORE..1
(-6175 725);
FORCEPROP 3 LASTPIN (-6175 675) SIG_NAME P12V_STBY\g
J 0
(-6165 685);
DISPLAY 0.659574 (-6165 685);
PAINT MONO (-6165 685);
DISPLAY INVISIBLE (-6165 685);
FORCEPROP 1 LAST HDL_POWER P12V_STBY
J 1
(-6175 775);
DISPLAY 0.489362 (-6175 775);
PAINT GREEN (-6175 775);
FORCEPROP 2 LAST CDS_LIB pure_quanta_power
J 0
(-6175 725);
DISPLAY INVISIBLE (-6175 725);
FORCEPROP 1 LAST PATH I229
J 0
(-6125 750);
DISPLAY 0.872340 (-6125 750);
PAINT AQUA (-6125 750);
DISPLAY INVISIBLE (-6125 750);
FORCEADD Q_RES..2
(-5600 1250);
FORCEPROP 1 LAST LOCATION PR126
J 0
(-5550 1300);
DISPLAY 0.489362 (-5550 1300);
PAINT SKYBLUE (-5550 1300);
FORCEPROP 0 LAST $SEC 1
J 0
(-5550 1325);
DISPLAY 0.680851 (-5550 1325);
PAINT MONO (-5550 1325);
DISPLAY INVISIBLE (-5550 1325);
FORCEPROP 0 LAST CDS_SEC 1
J 0
(-5550 1325);
DISPLAY 1.021277 (-5550 1325);
DISPLAY INVISIBLE (-5550 1325);
FORCEPROP 1 LASTPIN (-5600 1350) $PN 1
J 0
(-5595 1312);
DISPLAY 0.489362 (-5595 1312);
PAINT MONO (-5595 1312);
FORCEPROP 1 LASTPIN (-5600 1150) $PN 2
J 0
(-5595 1160);
DISPLAY 0.489362 (-5595 1160);
PAINT MONO (-5595 1160);
FORCEPROP 1 LAST PACK_TYPE 0402LF
J 0
(-5550 1150);
DISPLAY 0.489362 (-5550 1150);
PAINT SKYBLUE (-5550 1150);
FORCEPROP 1 LAST WATTAGE 1/16W
J 0
(-5550 1225);
DISPLAY 0.489362 (-5550 1225);
PAINT SKYBLUE (-5550 1225);
FORCEPROP 1 LAST MATERIAL CHIP
J 0
(-5550 1200);
DISPLAY 0.489362 (-5550 1200);
PAINT SKYBLUE (-5550 1200);
FORCEPROP 1 LAST TOLERANCE 1%
J 0
(-5550 1250);
DISPLAY 0.489362 (-5550 1250);
PAINT SKYBLUE (-5550 1250);
FORCEPROP 1 LAST VALUE 3.09K
J 0
(-5550 1275);
DISPLAY 0.489362 (-5550 1275);
PAINT SKYBLUE (-5550 1275);
FORCEPROP 1 LAST PART_NUMBER CS23092FB00
J 0
(-5550 1175);
DISPLAY 0.489362 (-5550 1175);
PAINT SKYBLUE (-5550 1175);
FORCEPROP 2 LAST CDS_LIB pure_quanta
J 0
(-5600 1250);
DISPLAY INVISIBLE (-5600 1250);
FORCEPROP 1 LAST PATH I3
J 0
(-5550 1425);
DISPLAY 0.978723 (-5550 1425);
PAINT WHITE (-5550 1425);
DISPLAY INVISIBLE (-5550 1425);
FORCEADD Q_CAP..1
(-3375 700);
FORCEPROP 1 LAST LOCATION PC198
J 0
(-3325 800);
DISPLAY 0.489362 (-3325 800);
PAINT SKYBLUE (-3325 800);
FORCEPROP 0 LAST $SEC 1
J 0
(-3325 825);
DISPLAY 0.680851 (-3325 825);
PAINT MONO (-3325 825);
DISPLAY INVISIBLE (-3325 825);
FORCEPROP 0 LAST CDS_SEC 1
J 0
(-3325 825);
DISPLAY 1.021277 (-3325 825);
DISPLAY INVISIBLE (-3325 825);
FORCEPROP 1 LASTPIN (-3375 800) $PN 1
J 0
(-3365 780);
DISPLAY 0.489362 (-3365 780);
PAINT MONO (-3365 780);
FORCEPROP 1 LASTPIN (-3375 600) $PN 2
J 0
(-3365 580);
DISPLAY 0.489362 (-3365 580);
PAINT MONO (-3365 580);
FORCEPROP 1 LAST MATERIAL X7R
J 0
(-3325 600);
DISPLAY 0.489362 (-3325 600);
PAINT SKYBLUE (-3325 600);
FORCEPROP 1 LAST TOLERANCE 10%
J 0
(-3325 650);
DISPLAY 0.489362 (-3325 650);
PAINT SKYBLUE (-3325 650);
FORCEPROP 1 LAST VALUE 470PF
J 0
(-3325 750);
DISPLAY 0.489362 (-3325 750);
PAINT SKYBLUE (-3325 750);
FORCEPROP 1 LAST PART_NUMBER TMP_QCH14706KB18
J 0
(-3325 550);
DISPLAY 0.489362 (-3325 550);
PAINT SKYBLUE (-3325 550);
FORCEPROP 1 LAST VOLTAGE 50V
J 0
(-3325 700);
DISPLAY 0.489362 (-3325 700);
PAINT SKYBLUE (-3325 700);
FORCEPROP 1 LAST PACK_TYPE 0402
J 0
(-3325 500);
DISPLAY 0.489362 (-3325 500);
PAINT SKYBLUE (-3325 500);
FORCEPROP 2 LAST CDS_LIB pure_quanta
J 0
(-3375 700);
DISPLAY INVISIBLE (-3375 700);
FORCEPROP 1 LAST PATH I36
J 0
(-3325 850);
DISPLAY 0.978723 (-3325 850);
PAINT WHITE (-3325 850);
DISPLAY INVISIBLE (-3325 850);
FORCEADD UNIVERSAL_GND..1
(-3375 425);
FORCEPROP 3 LASTPIN (-3375 475) SIG_NAME GND\g
J 0
(-3365 485);
DISPLAY 0.659574 (-3365 485);
PAINT MONO (-3365 485);
DISPLAY INVISIBLE (-3365 485);
FORCEPROP 2 LAST CDS_LIB pure_quanta_power
J 0
(-3375 425);
DISPLAY INVISIBLE (-3375 425);
FORCEPROP 1 LAST PATH I37
J 0
(-3300 425);
DISPLAY 0.872340 (-3300 425);
PAINT AQUA (-3300 425);
DISPLAY INVISIBLE (-3300 425);
FORCEPROP 1 LAST HDL_POWER GND
J 1
(-3350 350);
DISPLAY 0.872340 (-3350 350);
PAINT GREEN (-3350 350);
DISPLAY INVISIBLE (-3350 350);
FORCEADD Q_RES..1
(-5900 5950);
FORCEPROP 1 LAST LOCATION PR123
J 0
(-5950 5975);
DISPLAY 0.489362 (-5950 5975);
PAINT SKYBLUE (-5950 5975);
FORCEPROP 0 LAST $SEC 1
J 0
(-5775 6000);
DISPLAY 0.680851 (-5775 6000);
PAINT MONO (-5775 6000);
DISPLAY INVISIBLE (-5775 6000);
FORCEPROP 0 LAST CDS_SEC 1
J 0
(-5775 6000);
DISPLAY 1.021277 (-5775 6000);
DISPLAY INVISIBLE (-5775 6000);
FORCEPROP 1 LASTPIN (-6000 5950) $PN 1
J 0
(-5988 5962);
DISPLAY 0.489362 (-5988 5962);
PAINT MONO (-5988 5962);
FORCEPROP 1 LASTPIN (-5800 5950) $PN 2
J 0
(-5838 5962);
DISPLAY 0.489362 (-5838 5962);
PAINT MONO (-5838 5962);
FORCEPROP 1 LAST WATTAGE 1/16W
J 0
(-5800 5900);
DISPLAY 0.489362 (-5800 5900);
PAINT SKYBLUE (-5800 5900);
FORCEPROP 1 LAST MATERIAL CHIP
J 0
(-6150 5875);
DISPLAY 0.489362 (-6150 5875);
PAINT SKYBLUE (-6150 5875);
FORCEPROP 1 LAST TOLERANCE 5%
J 0
(-5775 5975);
DISPLAY 0.489362 (-5775 5975);
PAINT SKYBLUE (-5775 5975);
FORCEPROP 1 LAST VALUE 0
J 2
(-6025 5975);
DISPLAY 0.489362 (-6025 5975);
PAINT SKYBLUE (-6025 5975);
FORCEPROP 1 LAST PART_NUMBER CS00002JB38
J 0
(-6150 5900);
DISPLAY 0.489362 (-6150 5900);
PAINT SKYBLUE (-6150 5900);
FORCEPROP 1 LAST PACK_TYPE 0402LF
J 0
(-5800 5875);
DISPLAY 0.489362 (-5800 5875);
PAINT SKYBLUE (-5800 5875);
FORCEPROP 2 LAST CDS_LIB pure_quanta
J 0
(-5900 5950);
DISPLAY INVISIBLE (-5900 5950);
FORCEPROP 1 LAST PATH I47
J 0
(-5950 6100);
DISPLAY 0.978723 (-5950 6100);
PAINT WHITE (-5950 6100);
DISPLAY INVISIBLE (-5950 6100);
FORCEADD Q_CAP..2
(-5225 5825);
FORCEPROP 1 LAST LOCATION PC197
J 1
(-5225 5875);
DISPLAY 0.489362 (-5225 5875);
PAINT SKYBLUE (-5225 5875);
FORCEPROP 0 LAST $SEC 1
J 0
(-5225 5925);
DISPLAY 0.680851 (-5225 5925);
PAINT MONO (-5225 5925);
DISPLAY INVISIBLE (-5225 5925);
FORCEPROP 0 LAST CDS_SEC 1
J 0
(-5225 5925);
DISPLAY 1.021277 (-5225 5925);
DISPLAY INVISIBLE (-5225 5925);
FORCEPROP 1 LASTPIN (-5325 5825) $PN 1
J 0
(-5335 5840);
DISPLAY 0.489362 (-5335 5840);
PAINT MONO (-5335 5840);
FORCEPROP 1 LASTPIN (-5125 5825) $PN 2
J 0
(-5140 5840);
DISPLAY 0.489362 (-5140 5840);
PAINT MONO (-5140 5840);
FORCEPROP 1 LAST MATERIAL X7R
J 0
(-5650 5775);
DISPLAY 0.489362 (-5650 5775);
PAINT SKYBLUE (-5650 5775);
FORCEPROP 1 LAST TOLERANCE 5%
J 0
(-5125 5775);
DISPLAY 0.489362 (-5125 5775);
PAINT SKYBLUE (-5125 5775);
FORCEPROP 1 LAST VALUE 1000PF
J 2
(-5400 5850);
DISPLAY 0.489362 (-5400 5850);
PAINT SKYBLUE (-5400 5850);
FORCEPROP 1 LAST PART_NUMBER TMP_QCH21006JB10
J 0
(-5650 5800);
DISPLAY 0.489362 (-5650 5800);
PAINT SKYBLUE (-5650 5800);
FORCEPROP 1 LAST VOLTAGE 50V
J 0
(-5075 5850);
DISPLAY 0.489362 (-5075 5850);
PAINT SKYBLUE (-5075 5850);
FORCEPROP 1 LAST PACK_TYPE 0402
J 0
(-5125 5800);
DISPLAY 0.489362 (-5125 5800);
PAINT SKYBLUE (-5125 5800);
FORCEPROP 2 LAST CDS_LIB pure_quanta
J 0
(-5225 5825);
DISPLAY INVISIBLE (-5225 5825);
FORCEPROP 1 LAST PATH I49
J 0
(-5225 6025);
DISPLAY 0.978723 (-5225 6025);
PAINT WHITE (-5225 6025);
DISPLAY INVISIBLE (-5225 6025);
FORCEADD UNIVERSAL_GND..1
(-5600 1050);
FORCEPROP 3 LASTPIN (-5600 1100) SIG_NAME GND\g
J 0
(-5590 1110);
DISPLAY 0.659574 (-5590 1110);
PAINT MONO (-5590 1110);
DISPLAY INVISIBLE (-5590 1110);
FORCEPROP 2 LAST CDS_LIB pure_quanta_power
J 0
(-5600 1050);
DISPLAY INVISIBLE (-5600 1050);
FORCEPROP 1 LAST PATH I5
J 0
(-5525 1050);
DISPLAY 0.872340 (-5525 1050);
PAINT AQUA (-5525 1050);
DISPLAY INVISIBLE (-5525 1050);
FORCEPROP 1 LAST HDL_POWER GND
J 1
(-5575 975);
DISPLAY 0.872340 (-5575 975);
PAINT GREEN (-5575 975);
DISPLAY INVISIBLE (-5575 975);
FORCEADD UNIVERSAL_GND..1
(-5000 5750);
FORCEPROP 3 LASTPIN (-5000 5800) SIG_NAME GND\g
J 0
(-4990 5810);
DISPLAY 0.659574 (-4990 5810);
PAINT MONO (-4990 5810);
DISPLAY INVISIBLE (-4990 5810);
FORCEPROP 2 LAST CDS_LIB pure_quanta_power
J 0
(-5000 5750);
DISPLAY INVISIBLE (-5000 5750);
FORCEPROP 1 LAST PATH I50
J 0
(-4925 5750);
DISPLAY 0.872340 (-4925 5750);
PAINT AQUA (-4925 5750);
DISPLAY INVISIBLE (-4925 5750);
FORCEPROP 1 LAST HDL_POWER GND
J 1
(-4975 5675);
DISPLAY 0.872340 (-4975 5675);
PAINT GREEN (-4975 5675);
DISPLAY INVISIBLE (-4975 5675);
FORCEADD Q_RES..1
(-5975 4950);
FORCEPROP 1 LAST LOCATION PR118
J 0
(-6025 5000);
DISPLAY 0.489362 (-6025 5000);
PAINT SKYBLUE (-6025 5000);
FORCEPROP 0 LAST $SEC 1
J 0
(-6025 5025);
DISPLAY 0.680851 (-6025 5025);
PAINT MONO (-6025 5025);
DISPLAY INVISIBLE (-6025 5025);
FORCEPROP 0 LAST CDS_SEC 1
J 0
(-6025 5025);
DISPLAY 1.021277 (-6025 5025);
DISPLAY INVISIBLE (-6025 5025);
FORCEPROP 1 LASTPIN (-6075 4950) $PN 1
J 0
(-6063 4962);
DISPLAY 0.489362 (-6063 4962);
PAINT MONO (-6063 4962);
FORCEPROP 1 LASTPIN (-5875 4950) $PN 2
J 0
(-5913 4962);
DISPLAY 0.489362 (-5913 4962);
PAINT MONO (-5913 4962);
FORCEPROP 1 LAST WATTAGE 1/16W
J 0
(-5875 4900);
DISPLAY 0.489362 (-5875 4900);
PAINT SKYBLUE (-5875 4900);
FORCEPROP 1 LAST MATERIAL CHIP
J 0
(-6225 4875);
DISPLAY 0.489362 (-6225 4875);
PAINT SKYBLUE (-6225 4875);
FORCEPROP 1 LAST TOLERANCE 5%
J 0
(-5850 4975);
DISPLAY 0.489362 (-5850 4975);
PAINT SKYBLUE (-5850 4975);
FORCEPROP 1 LAST VALUE 0
J 2
(-6100 4975);
DISPLAY 0.489362 (-6100 4975);
PAINT SKYBLUE (-6100 4975);
FORCEPROP 1 LAST PART_NUMBER CS00002JB38
J 0
(-6225 4900);
DISPLAY 0.489362 (-6225 4900);
PAINT SKYBLUE (-6225 4900);
FORCEPROP 1 LAST PACK_TYPE 0402LF
J 0
(-5875 4875);
DISPLAY 0.489362 (-5875 4875);
PAINT SKYBLUE (-5875 4875);
FORCEPROP 2 LAST CDS_LIB pure_quanta
J 0
(-5975 4950);
DISPLAY INVISIBLE (-5975 4950);
FORCEPROP 1 LAST PATH I66
J 0
(-6025 5100);
DISPLAY 0.978723 (-6025 5100);
PAINT WHITE (-6025 5100);
DISPLAY INVISIBLE (-6025 5100);
FORCEADD Q_RES..1
(-5975 4800);
FORCEPROP 1 LAST LOCATION PR119
J 0
(-6025 4850);
DISPLAY 0.489362 (-6025 4850);
PAINT SKYBLUE (-6025 4850);
FORCEPROP 0 LAST $SEC 1
J 0
(-6025 4875);
DISPLAY 0.680851 (-6025 4875);
PAINT MONO (-6025 4875);
DISPLAY INVISIBLE (-6025 4875);
FORCEPROP 0 LAST CDS_SEC 1
J 0
(-6025 4875);
DISPLAY 1.021277 (-6025 4875);
DISPLAY INVISIBLE (-6025 4875);
FORCEPROP 1 LASTPIN (-6075 4800) $PN 1
J 0
(-6063 4812);
DISPLAY 0.489362 (-6063 4812);
PAINT MONO (-6063 4812);
FORCEPROP 1 LASTPIN (-5875 4800) $PN 2
J 0
(-5913 4812);
DISPLAY 0.489362 (-5913 4812);
PAINT MONO (-5913 4812);
FORCEPROP 1 LAST WATTAGE 1/16W
J 0
(-5875 4750);
DISPLAY 0.489362 (-5875 4750);
PAINT SKYBLUE (-5875 4750);
FORCEPROP 1 LAST MATERIAL CHIP
J 0
(-6225 4725);
DISPLAY 0.489362 (-6225 4725);
PAINT SKYBLUE (-6225 4725);
FORCEPROP 1 LAST TOLERANCE 5%
J 0
(-5850 4825);
DISPLAY 0.489362 (-5850 4825);
PAINT SKYBLUE (-5850 4825);
FORCEPROP 1 LAST VALUE 0
J 2
(-6100 4825);
DISPLAY 0.489362 (-6100 4825);
PAINT SKYBLUE (-6100 4825);
FORCEPROP 1 LAST PART_NUMBER CS00002JB38
J 0
(-6225 4750);
DISPLAY 0.489362 (-6225 4750);
PAINT SKYBLUE (-6225 4750);
FORCEPROP 1 LAST PACK_TYPE 0402LF
J 0
(-5875 4725);
DISPLAY 0.489362 (-5875 4725);
PAINT SKYBLUE (-5875 4725);
FORCEPROP 2 LAST CDS_LIB pure_quanta
J 0
(-5975 4800);
DISPLAY INVISIBLE (-5975 4800);
FORCEPROP 1 LAST PATH I67
J 0
(-6025 4950);
DISPLAY 0.978723 (-6025 4950);
PAINT WHITE (-6025 4950);
DISPLAY INVISIBLE (-6025 4950);
FORCEADD Q_RES..1
(-5975 4650);
FORCEPROP 1 LAST LOCATION PR120
J 0
(-6025 4700);
DISPLAY 0.489362 (-6025 4700);
PAINT SKYBLUE (-6025 4700);
FORCEPROP 0 LAST $SEC 1
J 0
(-6025 4725);
DISPLAY 0.680851 (-6025 4725);
PAINT MONO (-6025 4725);
DISPLAY INVISIBLE (-6025 4725);
FORCEPROP 0 LAST CDS_SEC 1
J 0
(-6025 4725);
DISPLAY 1.021277 (-6025 4725);
DISPLAY INVISIBLE (-6025 4725);
FORCEPROP 1 LASTPIN (-6075 4650) $PN 1
J 0
(-6063 4662);
DISPLAY 0.489362 (-6063 4662);
PAINT MONO (-6063 4662);
FORCEPROP 1 LASTPIN (-5875 4650) $PN 2
J 0
(-5913 4662);
DISPLAY 0.489362 (-5913 4662);
PAINT MONO (-5913 4662);
FORCEPROP 1 LAST WATTAGE 1/16W
J 0
(-5875 4600);
DISPLAY 0.489362 (-5875 4600);
PAINT SKYBLUE (-5875 4600);
FORCEPROP 1 LAST MATERIAL CHIP
J 0
(-6225 4575);
DISPLAY 0.489362 (-6225 4575);
PAINT SKYBLUE (-6225 4575);
FORCEPROP 1 LAST TOLERANCE 5%
J 0
(-5850 4675);
DISPLAY 0.489362 (-5850 4675);
PAINT SKYBLUE (-5850 4675);
FORCEPROP 1 LAST VALUE 0
J 2
(-6100 4675);
DISPLAY 0.489362 (-6100 4675);
PAINT SKYBLUE (-6100 4675);
FORCEPROP 1 LAST PART_NUMBER CS00002JB38
J 0
(-6225 4600);
DISPLAY 0.489362 (-6225 4600);
PAINT SKYBLUE (-6225 4600);
FORCEPROP 1 LAST PACK_TYPE 0402LF
J 0
(-5875 4575);
DISPLAY 0.489362 (-5875 4575);
PAINT SKYBLUE (-5875 4575);
FORCEPROP 2 LAST CDS_LIB pure_quanta
J 0
(-5975 4650);
DISPLAY INVISIBLE (-5975 4650);
FORCEPROP 1 LAST PATH I68
J 0
(-6025 4800);
DISPLAY 0.978723 (-6025 4800);
PAINT WHITE (-6025 4800);
DISPLAY INVISIBLE (-6025 4800);
FORCEADD RAA229621GNPHA0..1
(-4325 3350);
FORCEPROP 1 LAST LOCATION PU21
J 0
(-4875 6375);
DISPLAY 0.489362 (-4875 6375);
PAINT SKYBLUE (-4875 6375);
FORCEPROP 0 LAST $SEC 1
J 0
(-4850 6550);
DISPLAY 0.680851 (-4850 6550);
PAINT MONO (-4850 6550);
DISPLAY INVISIBLE (-4850 6550);
FORCEPROP 0 LAST CDS_SEC 1
J 0
(-4850 6550);
DISPLAY 1.021277 (-4850 6550);
DISPLAY INVISIBLE (-4850 6550);
FORCEPROP 0 LASTPIN (-3675 1850) $PN 30
J 0
(-3665 1860);
DISPLAY 0.489362 (-3665 1860);
PAINT MONO (-3665 1860);
FORCEPROP 0 LASTPIN (-3675 2300) $PN 29
J 0
(-3665 2310);
DISPLAY 0.489362 (-3665 2310);
PAINT MONO (-3665 2310);
FORCEPROP 0 LASTPIN (-3675 2750) $PN 28
J 0
(-3665 2760);
DISPLAY 0.489362 (-3665 2760);
PAINT MONO (-3665 2760);
FORCEPROP 0 LASTPIN (-3675 3200) $PN 27
J 0
(-3665 3210);
DISPLAY 0.489362 (-3665 3210);
PAINT MONO (-3665 3210);
FORCEPROP 0 LASTPIN (-3675 3650) $PN 26
J 0
(-3665 3660);
DISPLAY 0.489362 (-3665 3660);
PAINT MONO (-3665 3660);
FORCEPROP 0 LASTPIN (-3675 4100) $PN 25
J 0
(-3665 4110);
DISPLAY 0.489362 (-3665 4110);
PAINT MONO (-3665 4110);
FORCEPROP 0 LASTPIN (-3675 4550) $PN 24
J 0
(-3665 4560);
DISPLAY 0.489362 (-3665 4560);
PAINT MONO (-3665 4560);
FORCEPROP 0 LASTPIN (-3675 5000) $PN 23
J 0
(-3665 5010);
DISPLAY 0.489362 (-3665 5010);
PAINT MONO (-3665 5010);
FORCEPROP 0 LASTPIN (-5025 5950) $PN 13
J 2
(-5035 5960);
DISPLAY 0.489362 (-5035 5960);
PAINT MONO (-5035 5960);
FORCEPROP 0 LASTPIN (-5025 1400) $PN 34
J 2
(-5035 1410);
DISPLAY 0.489362 (-5035 1410);
PAINT MONO (-5035 1410);
FORCEPROP 0 LASTPIN (-5025 4650) $PN 11
J 2
(-5035 4660);
DISPLAY 0.489362 (-5035 4660);
PAINT MONO (-5035 4660);
FORCEPROP 0 LASTPIN (-5025 2100) $PN 33
J 2
(-5035 2110);
DISPLAY 0.489362 (-5035 2110);
PAINT MONO (-5035 2110);
FORCEPROP 0 LASTPIN (-5025 6100) $PN 12
J 2
(-5035 6110);
DISPLAY 0.489362 (-5035 6110);
PAINT MONO (-5035 6110);
FORCEPROP 0 LASTPIN (-5025 850) $PN 16
J 2
(-5035 860);
DISPLAY 0.489362 (-5035 860);
PAINT MONO (-5035 860);
FORCEPROP 0 LASTPIN (-5025 4950) $PN 10
J 2
(-5035 4960);
DISPLAY 0.489362 (-5035 4960);
PAINT MONO (-5035 4960);
FORCEPROP 0 LASTPIN (-5025 4800) $PN 9
J 2
(-5035 4810);
DISPLAY 0.489362 (-5035 4810);
PAINT MONO (-5035 4810);
FORCEPROP 0 LASTPIN (-3675 1950) $PN 1
J 0
(-3665 1960);
DISPLAY 0.489362 (-3665 1960);
PAINT MONO (-3665 1960);
FORCEPROP 0 LASTPIN (-3675 2400) $PN 2
J 0
(-3665 2410);
DISPLAY 0.489362 (-3665 2410);
PAINT MONO (-3665 2410);
FORCEPROP 0 LASTPIN (-3675 2850) $PN 3
J 0
(-3665 2860);
DISPLAY 0.489362 (-3665 2860);
PAINT MONO (-3665 2860);
FORCEPROP 0 LASTPIN (-3675 3300) $PN 4
J 0
(-3665 3310);
DISPLAY 0.489362 (-3665 3310);
PAINT MONO (-3665 3310);
FORCEPROP 0 LASTPIN (-3675 3750) $PN 5
J 0
(-3665 3760);
DISPLAY 0.489362 (-3665 3760);
PAINT MONO (-3665 3760);
FORCEPROP 0 LASTPIN (-3675 4200) $PN 6
J 0
(-3665 4210);
DISPLAY 0.489362 (-3665 4210);
PAINT MONO (-3665 4210);
FORCEPROP 0 LASTPIN (-3675 4650) $PN 7
J 0
(-3665 4660);
DISPLAY 0.489362 (-3665 4660);
PAINT MONO (-3665 4660);
FORCEPROP 0 LASTPIN (-3675 5100) $PN 8
J 0
(-3665 5110);
DISPLAY 0.489362 (-3665 5110);
PAINT MONO (-3665 5110);
FORCEPROP 0 LASTPIN (-3675 1600) $PN 14
J 0
(-3665 1610);
DISPLAY 0.489362 (-3665 1610);
PAINT MONO (-3665 1610);
FORCEPROP 0 LASTPIN (-5025 3800) $PN 22
J 2
(-5035 3810);
DISPLAY 0.489362 (-5035 3810);
PAINT MONO (-5035 3810);
FORCEPROP 0 LASTPIN (-5025 2700) $PN 31
J 2
(-5035 2710);
DISPLAY 0.489362 (-5035 2710);
PAINT MONO (-5035 2710);
FORCEPROP 0 LASTPIN (-5025 5650) $PN 18
J 2
(-5035 5660);
DISPLAY 0.489362 (-5035 5660);
PAINT MONO (-5035 5660);
FORCEPROP 0 LASTPIN (-5025 5500) $PN 17
J 2
(-5035 5510);
DISPLAY 0.489362 (-5035 5510);
PAINT MONO (-5035 5510);
FORCEPROP 0 LASTPIN (-5025 5200) $PN 20
J 2
(-5035 5210);
DISPLAY 0.489362 (-5035 5210);
PAINT MONO (-5035 5210);
FORCEPROP 0 LASTPIN (-5025 5350) $PN 19
J 2
(-5035 5360);
DISPLAY 0.489362 (-5035 5360);
PAINT MONO (-5035 5360);
FORCEPROP 0 LASTPIN (-3675 900) $PN 36
J 0
(-3665 910);
DISPLAY 0.489362 (-3665 910);
PAINT MONO (-3665 910);
FORCEPROP 0 LASTPIN (-3675 1200) $PN 35
J 0
(-3665 1210);
DISPLAY 0.489362 (-3665 1210);
PAINT MONO (-3665 1210);
FORCEPROP 0 LASTPIN (-5025 550) $PN TH
J 2
(-5035 560);
DISPLAY 0.489362 (-5035 560);
PAINT MONO (-5035 560);
FORCEPROP 0 LASTPIN (-3675 6100) $PN 39
J 0
(-3665 6110);
DISPLAY 0.489362 (-3665 6110);
PAINT MONO (-3665 6110);
FORCEPROP 0 LASTPIN (-3675 5800) $PN 40
J 0
(-3665 5810);
DISPLAY 0.489362 (-3665 5810);
PAINT MONO (-3665 5810);
FORCEPROP 0 LASTPIN (-5025 1850) $PN 15
J 2
(-5035 1860);
DISPLAY 0.489362 (-5035 1860);
PAINT MONO (-5035 1860);
FORCEPROP 0 LASTPIN (-5025 650) $PN 38
J 2
(-5035 660);
DISPLAY 0.489362 (-5035 660);
PAINT MONO (-5035 660);
FORCEPROP 0 LASTPIN (-5025 750) $PN 37
J 2
(-5035 760);
DISPLAY 0.489362 (-5035 760);
PAINT MONO (-5035 760);
FORCEPROP 0 LASTPIN (-5025 4050) $PN 21
J 2
(-5035 4060);
DISPLAY 0.489362 (-5035 4060);
PAINT MONO (-5035 4060);
FORCEPROP 0 LASTPIN (-5025 2950) $PN 32
J 2
(-5035 2960);
DISPLAY 0.489362 (-5035 2960);
PAINT MONO (-5035 2960);
FORCEPROP 1 LAST PART_NUMBER AR0T6GPV006
J 0
(-4875 6300);
DISPLAY 0.489362 (-4875 6300);
PAINT SKYBLUE (-4875 6300);
FORCEPROP 2 LAST VALUE RAA229621GNP#HA0
J 0
(-4875 6450);
DISPLAY 0.489362 (-4875 6450);
PAINT SKYBLUE (-4875 6450);
FORCEPROP 1 LAST MATERIAL IC
J 0
(-4875 6225);
DISPLAY 0.489362 (-4875 6225);
PAINT SKYBLUE (-4875 6225);
FORCEPROP 2 LAST PART_TYPE SMLF
J 0
(-4875 6500);
DISPLAY 1.021277 (-4875 6500);
FORCEPROP 1 LAST PATH I7
J 0
(-4325 3350);
DISPLAY 0.723404 (-4325 3350);
PAINT GREEN (-4325 3350);
DISPLAY INVISIBLE (-4325 3350);
FORCEPROP 2 LAST CDS_LIB pure_quanta
J 0
(-4325 3350);
DISPLAY INVISIBLE (-4325 3350);
FORCEPROP 1 LAST NEEDS_NO_SIZE TRUE
J 0
(-4325 3350);
DISPLAY 0.723404 (-4325 3350);
PAINT GREEN (-4325 3350);
DISPLAY INVISIBLE (-4325 3350);
FORCEPROP 1 LAST CDS_LMAN_SYM_OUTLINE -550,2850,500,-2850
J 0
(-4325 3350);
DISPLAY 0.468085 (-4325 3350);
PAINT GREEN (-4325 3350);
DISPLAY INVISIBLE (-4325 3350);
FORCEADD OFFPAGE..2
R 2
(-6750 4950);
FORCEPROP 2 LAST $XR0 118 
J 0
(-7005 4950);
DISPLAY 0.638298 (-7005 4950);
PAINT MONO (-7005 4950);
FORCEPROP 2 LAST CDS_LIB standard
J 0
(-6750 4950);
DISPLAY INVISIBLE (-6750 4950);
FORCEPROP 2 LAST PATH I73
J 0
(-6700 5025);
DISPLAY 1.021277 (-6700 5025);
DISPLAY INVISIBLE (-6700 5025);
FORCEPROP 1 LAST COMMENT_BODY TRUE
J 2
(-6705 4855);
DISPLAY 0.872340 (-6705 4855);
PAINT GREEN (-6705 4855);
DISPLAY INVISIBLE (-6705 4855);
FORCEPROP 1 LAST OFFPAGE TRUE
J 2
(-7075 4825);
DISPLAY 0.872340 (-7075 4825);
PAINT GREEN (-7075 4825);
DISPLAY INVISIBLE (-7075 4825);
FORCEADD OFFPAGE..2
R 2
(-6750 4800);
FORCEPROP 2 LAST $XR0 118 
J 0
(-7005 4800);
DISPLAY 0.638298 (-7005 4800);
PAINT MONO (-7005 4800);
FORCEPROP 2 LAST PATH I74
J 0
(-6700 4875);
DISPLAY 1.021277 (-6700 4875);
DISPLAY INVISIBLE (-6700 4875);
FORCEPROP 2 LAST CDS_LIB standard
J 0
(-6750 4800);
DISPLAY INVISIBLE (-6750 4800);
FORCEPROP 1 LAST COMMENT_BODY TRUE
J 2
(-6705 4705);
DISPLAY 0.872340 (-6705 4705);
PAINT GREEN (-6705 4705);
DISPLAY INVISIBLE (-6705 4705);
FORCEPROP 1 LAST OFFPAGE TRUE
J 2
(-7075 4675);
DISPLAY 0.872340 (-7075 4675);
PAINT GREEN (-7075 4675);
DISPLAY INVISIBLE (-7075 4675);
FORCEADD OFFPAGE..2
R 2
(-6750 4650);
FORCEPROP 2 LAST $XR1 81 
J 0
(-7064 4650);
DISPLAY 0.638298 (-7064 4650);
PAINT MONO (-7064 4650);
FORCEPROP 2 LAST $XR0 82 
J 0
(-6974 4650);
DISPLAY 0.638298 (-6974 4650);
PAINT MONO (-6974 4650);
FORCEPROP 2 LAST PATH I75
J 0
(-6700 4725);
DISPLAY 1.021277 (-6700 4725);
DISPLAY INVISIBLE (-6700 4725);
FORCEPROP 2 LAST CDS_LIB standard
J 0
(-6750 4650);
DISPLAY INVISIBLE (-6750 4650);
FORCEPROP 1 LAST COMMENT_BODY TRUE
J 2
(-6705 4555);
DISPLAY 0.872340 (-6705 4555);
PAINT GREEN (-6705 4555);
DISPLAY INVISIBLE (-6705 4555);
FORCEPROP 1 LAST OFFPAGE TRUE
J 2
(-7075 4525);
DISPLAY 0.872340 (-7075 4525);
PAINT GREEN (-7075 4525);
DISPLAY INVISIBLE (-7075 4525);
FORCEADD Q_CAP..1
(-5675 3925);
FORCEPROP 1 LAST LOCATION PC194
J 0
(-5625 3975);
DISPLAY 0.489362 (-5625 3975);
PAINT SKYBLUE (-5625 3975);
FORCEPROP 0 LAST $SEC 1
J 0
(-5625 4000);
DISPLAY 0.680851 (-5625 4000);
PAINT MONO (-5625 4000);
DISPLAY INVISIBLE (-5625 4000);
FORCEPROP 0 LAST CDS_SEC 1
J 0
(-5625 4000);
DISPLAY 1.021277 (-5625 4000);
DISPLAY INVISIBLE (-5625 4000);
FORCEPROP 1 LASTPIN (-5675 4025) $PN 1
J 0
(-5665 4005);
DISPLAY 0.489362 (-5665 4005);
PAINT MONO (-5665 4005);
FORCEPROP 1 LASTPIN (-5675 3825) $PN 2
J 0
(-5665 3805);
DISPLAY 0.489362 (-5665 3805);
PAINT MONO (-5665 3805);
FORCEPROP 1 LAST MATERIAL X7R
J 0
(-5625 3875);
DISPLAY 0.489362 (-5625 3875);
PAINT SKYBLUE (-5625 3875);
FORCEPROP 1 LAST TOLERANCE 10%
J 0
(-5625 3900);
DISPLAY 0.489362 (-5625 3900);
PAINT SKYBLUE (-5625 3900);
FORCEPROP 1 LAST VALUE 3300PF
J 0
(-5625 3950);
DISPLAY 0.489362 (-5625 3950);
PAINT SKYBLUE (-5625 3950);
FORCEPROP 1 LAST PART_NUMBER TMP_QCH2336K1B12
J 0
(-5625 3850);
DISPLAY 0.489362 (-5625 3850);
PAINT SKYBLUE (-5625 3850);
FORCEPROP 1 LAST VOLTAGE 50V
J 0
(-5625 3925);
DISPLAY 0.489362 (-5625 3925);
PAINT SKYBLUE (-5625 3925);
FORCEPROP 1 LAST PACK_TYPE 0402
J 0
(-5625 3825);
DISPLAY 0.489362 (-5625 3825);
PAINT SKYBLUE (-5625 3825);
FORCEPROP 2 LAST CDS_LIB pure_quanta
J 0
(-5675 3925);
DISPLAY INVISIBLE (-5675 3925);
FORCEPROP 1 LAST PATH I76
J 0
(-5625 4075);
DISPLAY 0.978723 (-5625 4075);
PAINT WHITE (-5625 4075);
DISPLAY INVISIBLE (-5625 4075);
FORCEADD Q_RES..1
(-5975 4050);
FORCEPROP 1 LAST LOCATION PR121
J 0
(-6025 4100);
DISPLAY 0.489362 (-6025 4100);
PAINT SKYBLUE (-6025 4100);
FORCEPROP 0 LAST $SEC 1
J 0
(-6025 4125);
DISPLAY 0.680851 (-6025 4125);
PAINT MONO (-6025 4125);
DISPLAY INVISIBLE (-6025 4125);
FORCEPROP 0 LAST CDS_SEC 1
J 0
(-6025 4125);
DISPLAY 1.021277 (-6025 4125);
DISPLAY INVISIBLE (-6025 4125);
FORCEPROP 1 LASTPIN (-6075 4050) $PN 1
J 0
(-6063 4062);
DISPLAY 0.489362 (-6063 4062);
PAINT MONO (-6063 4062);
FORCEPROP 1 LASTPIN (-5875 4050) $PN 2
J 0
(-5913 4062);
DISPLAY 0.489362 (-5913 4062);
PAINT MONO (-5913 4062);
FORCEPROP 1 LAST WATTAGE 1/16W
J 0
(-5875 4000);
DISPLAY 0.489362 (-5875 4000);
PAINT SKYBLUE (-5875 4000);
FORCEPROP 1 LAST MATERIAL CHIP
J 0
(-6300 3975);
DISPLAY 0.489362 (-6300 3975);
PAINT SKYBLUE (-6300 3975);
FORCEPROP 1 LAST TOLERANCE 1%
J 0
(-5850 4075);
DISPLAY 0.489362 (-5850 4075);
PAINT SKYBLUE (-5850 4075);
FORCEPROP 1 LAST VALUE 10
J 2
(-6100 4075);
DISPLAY 0.489362 (-6100 4075);
PAINT SKYBLUE (-6100 4075);
FORCEPROP 1 LAST PART_NUMBER TMP_QCS01002FB21
J 0
(-6300 4000);
DISPLAY 0.489362 (-6300 4000);
PAINT SKYBLUE (-6300 4000);
FORCEPROP 1 LAST PACK_TYPE 0402LF
J 0
(-5875 3975);
DISPLAY 0.489362 (-5875 3975);
PAINT SKYBLUE (-5875 3975);
FORCEPROP 2 LAST CDS_LIB pure_quanta
J 0
(-5975 4050);
DISPLAY INVISIBLE (-5975 4050);
FORCEPROP 1 LAST PATH I77
J 0
(-6025 4200);
DISPLAY 0.978723 (-6025 4200);
PAINT WHITE (-6025 4200);
DISPLAY INVISIBLE (-6025 4200);
FORCEADD OFFPAGE..4
R 2
(-7475 4050);
FORCEPROP 2 LAST $XR0 27 
J 0
(-7816 4050);
DISPLAY 0.638298 (-7816 4050);
PAINT MONO (-7816 4050);
FORCEPROP 2 LAST PATH I79
J 2
(-7650 4125);
DISPLAY 1.021277 (-7650 4125);
DISPLAY INVISIBLE (-7650 4125);
FORCEPROP 2 LAST CDS_LIB standard
J 2
(-7475 4050);
DISPLAY INVISIBLE (-7475 4050);
FORCEPROP 1 LAST COMMENT_BODY TRUE
J 2
(-7450 3950);
DISPLAY 0.872340 (-7450 3950);
PAINT GREEN (-7450 3950);
DISPLAY INVISIBLE (-7450 3950);
FORCEPROP 1 LAST OFFPAGE TRUE
J 2
(-7800 3925);
DISPLAY 0.872340 (-7800 3925);
PAINT GREEN (-7800 3925);
DISPLAY INVISIBLE (-7800 3925);
FORCEADD Q_CAP..1
(-2925 6125);
FORCEPROP 1 LAST LOCATION PC200
J 0
(-2875 6225);
DISPLAY 0.489362 (-2875 6225);
PAINT SKYBLUE (-2875 6225);
FORCEPROP 0 LAST $SEC 1
J 0
(-2875 6250);
DISPLAY 0.680851 (-2875 6250);
PAINT MONO (-2875 6250);
DISPLAY INVISIBLE (-2875 6250);
FORCEPROP 0 LAST CDS_SEC 1
J 0
(-2875 6250);
DISPLAY 1.021277 (-2875 6250);
DISPLAY INVISIBLE (-2875 6250);
FORCEPROP 1 LASTPIN (-2925 6225) $PN 1
J 0
(-2915 6205);
DISPLAY 0.489362 (-2915 6205);
PAINT MONO (-2915 6205);
FORCEPROP 1 LASTPIN (-2925 6025) $PN 2
J 0
(-2915 6005);
DISPLAY 0.489362 (-2915 6005);
PAINT MONO (-2915 6005);
FORCEPROP 1 LAST MATERIAL X6S
J 0
(-2875 6025);
DISPLAY 0.489362 (-2875 6025);
PAINT SKYBLUE (-2875 6025);
FORCEPROP 1 LAST TOLERANCE 10%
J 0
(-2875 6075);
DISPLAY 0.489362 (-2875 6075);
PAINT SKYBLUE (-2875 6075);
FORCEPROP 1 LAST VALUE 1UF
J 0
(-2875 6175);
DISPLAY 0.489362 (-2875 6175);
PAINT SKYBLUE (-2875 6175);
FORCEPROP 1 LAST PART_NUMBER CH5103KEB01
J 0
(-2875 5975);
DISPLAY 0.489362 (-2875 5975);
PAINT SKYBLUE (-2875 5975);
FORCEPROP 1 LAST VOLTAGE 16V
J 0
(-2875 6125);
DISPLAY 0.489362 (-2875 6125);
PAINT SKYBLUE (-2875 6125);
FORCEPROP 1 LAST PACK_TYPE C0402
J 0
(-2875 5925);
DISPLAY 0.489362 (-2875 5925);
PAINT SKYBLUE (-2875 5925);
FORCEPROP 2 LAST CDS_LIB pure_quanta
J 0
(-2925 6125);
DISPLAY INVISIBLE (-2925 6125);
FORCEPROP 1 LAST PATH I8
J 0
(-2875 6275);
DISPLAY 0.978723 (-2875 6275);
PAINT WHITE (-2875 6275);
DISPLAY INVISIBLE (-2875 6275);
FORCEADD OFFPAGE..4
R 2
(-7475 3800);
FORCEPROP 2 LAST $XR1 176 
J 0
(-7936 3800);
DISPLAY 0.638298 (-7936 3800);
PAINT MONO (-7936 3800);
FORCEPROP 2 LAST $XR0 27 
J 0
(-7816 3800);
DISPLAY 0.638298 (-7816 3800);
PAINT MONO (-7816 3800);
FORCEPROP 2 LAST PATH I80
J 0
(-7425 3875);
DISPLAY 1.021277 (-7425 3875);
DISPLAY INVISIBLE (-7425 3875);
FORCEPROP 2 LAST CDS_LIB standard
J 0
(-7475 3800);
DISPLAY INVISIBLE (-7475 3800);
FORCEPROP 1 LAST COMMENT_BODY TRUE
J 2
(-7450 3700);
DISPLAY 0.872340 (-7450 3700);
PAINT GREEN (-7450 3700);
DISPLAY INVISIBLE (-7450 3700);
FORCEPROP 1 LAST OFFPAGE TRUE
J 2
(-7800 3675);
DISPLAY 0.872340 (-7800 3675);
PAINT GREEN (-7800 3675);
DISPLAY INVISIBLE (-7800 3675);
FORCEADD Q_RES..2
(-6800 4225);
FORCEPROP 1 LAST LOCATION PR114
J 0
(-6750 4350);
DISPLAY 0.489362 (-6750 4350);
PAINT SKYBLUE (-6750 4350);
FORCEPROP 0 LAST $SEC 1
J 0
(-6750 4375);
DISPLAY 0.680851 (-6750 4375);
PAINT MONO (-6750 4375);
DISPLAY INVISIBLE (-6750 4375);
FORCEPROP 0 LAST CDS_SEC 1
J 0
(-6750 4375);
DISPLAY 1.021277 (-6750 4375);
DISPLAY INVISIBLE (-6750 4375);
FORCEPROP 1 LASTPIN (-6800 4325) $PN 1
J 0
(-6795 4287);
DISPLAY 0.489362 (-6795 4287);
PAINT MONO (-6795 4287);
FORCEPROP 1 LASTPIN (-6800 4125) $PN 2
J 0
(-6795 4135);
DISPLAY 0.489362 (-6795 4135);
PAINT MONO (-6795 4135);
FORCEPROP 1 LAST WATTAGE 1/16W
J 0
(-6750 4200);
DISPLAY 0.489362 (-6750 4200);
PAINT SKYBLUE (-6750 4200);
FORCEPROP 1 LAST MATERIAL CHIP
J 0
(-6750 4150);
DISPLAY 0.489362 (-6750 4150);
PAINT SKYBLUE (-6750 4150);
FORCEPROP 1 LAST PART_NUMBER CS04992FB31
J 0
(-6750 4100);
DISPLAY 0.489362 (-6750 4100);
PAINT SKYBLUE (-6750 4100);
FORCEPROP 1 LAST PACK_TYPE 0402LF
J 0
(-6750 4050);
DISPLAY 0.489362 (-6750 4050);
PAINT SKYBLUE (-6750 4050);
FORCEPROP 1 LAST VALUE 49.9
J 0
(-6750 4300);
DISPLAY 0.489362 (-6750 4300);
PAINT SKYBLUE (-6750 4300);
FORCEPROP 1 LAST TOLERANCE 1%
J 0
(-6750 4250);
DISPLAY 0.489362 (-6750 4250);
PAINT SKYBLUE (-6750 4250);
FORCEPROP 2 LAST CDS_LIB pure_quanta
J 0
(-6800 4225);
DISPLAY INVISIBLE (-6800 4225);
FORCEPROP 1 LAST PATH I81
J 0
(-6750 4400);
DISPLAY 0.978723 (-6750 4400);
PAINT WHITE (-6750 4400);
DISPLAY INVISIBLE (-6750 4400);
FORCEADD Q_RES..2
(-6800 3650);
FORCEPROP 1 LAST LOCATION PR115
J 0
(-6750 3775);
DISPLAY 0.489362 (-6750 3775);
PAINT SKYBLUE (-6750 3775);
FORCEPROP 0 LAST $SEC 1
J 0
(-6750 3800);
DISPLAY 0.680851 (-6750 3800);
PAINT MONO (-6750 3800);
DISPLAY INVISIBLE (-6750 3800);
FORCEPROP 0 LAST CDS_SEC 1
J 0
(-6750 3800);
DISPLAY 1.021277 (-6750 3800);
DISPLAY INVISIBLE (-6750 3800);
FORCEPROP 1 LASTPIN (-6800 3750) $PN 1
J 0
(-6795 3712);
DISPLAY 0.489362 (-6795 3712);
PAINT MONO (-6795 3712);
FORCEPROP 1 LASTPIN (-6800 3550) $PN 2
J 0
(-6795 3560);
DISPLAY 0.489362 (-6795 3560);
PAINT MONO (-6795 3560);
FORCEPROP 1 LAST WATTAGE 1/16W
J 0
(-6750 3625);
DISPLAY 0.489362 (-6750 3625);
PAINT SKYBLUE (-6750 3625);
FORCEPROP 1 LAST MATERIAL CHIP
J 0
(-6750 3575);
DISPLAY 0.489362 (-6750 3575);
PAINT SKYBLUE (-6750 3575);
FORCEPROP 1 LAST PART_NUMBER CS04992FB31
J 0
(-6750 3525);
DISPLAY 0.489362 (-6750 3525);
PAINT SKYBLUE (-6750 3525);
FORCEPROP 1 LAST PACK_TYPE 0402LF
J 0
(-6750 3475);
DISPLAY 0.489362 (-6750 3475);
PAINT SKYBLUE (-6750 3475);
FORCEPROP 1 LAST VALUE 49.9
J 0
(-6750 3725);
DISPLAY 0.489362 (-6750 3725);
PAINT SKYBLUE (-6750 3725);
FORCEPROP 1 LAST TOLERANCE 1%
J 0
(-6750 3675);
DISPLAY 0.489362 (-6750 3675);
PAINT SKYBLUE (-6750 3675);
FORCEPROP 2 LAST CDS_LIB pure_quanta
J 0
(-6800 3650);
DISPLAY INVISIBLE (-6800 3650);
FORCEPROP 1 LAST PATH I82
J 0
(-6750 3825);
DISPLAY 0.978723 (-6750 3825);
PAINT WHITE (-6750 3825);
DISPLAY INVISIBLE (-6750 3825);
FORCEADD UNIVERSAL_GND..1
(-6800 3475);
FORCEPROP 3 LASTPIN (-6800 3525) SIG_NAME GND\g
J 0
(-6790 3535);
DISPLAY 0.659574 (-6790 3535);
PAINT MONO (-6790 3535);
DISPLAY INVISIBLE (-6790 3535);
FORCEPROP 2 LAST CDS_LIB pure_quanta_power
J 0
(-6800 3475);
DISPLAY INVISIBLE (-6800 3475);
FORCEPROP 1 LAST PATH I83
J 0
(-6725 3475);
DISPLAY 0.872340 (-6725 3475);
PAINT AQUA (-6725 3475);
DISPLAY INVISIBLE (-6725 3475);
FORCEPROP 1 LAST HDL_POWER GND
J 1
(-6775 3400);
DISPLAY 0.872340 (-6775 3400);
PAINT GREEN (-6775 3400);
DISPLAY INVISIBLE (-6775 3400);
FORCEADD VCC_CORE..1
(-6800 4425);
FORCEPROP 3 LASTPIN (-6800 4375) SIG_NAME PVDD11_S3_P0\g
J 0
(-6790 4385);
DISPLAY 0.659574 (-6790 4385);
PAINT MONO (-6790 4385);
DISPLAY INVISIBLE (-6790 4385);
FORCEPROP 1 LAST HDL_POWER PVDD11_S3_P0
J 1
(-6800 4475);
DISPLAY 0.489362 (-6800 4475);
PAINT GREEN (-6800 4475);
FORCEPROP 2 LAST CDS_LIB pure_quanta_power
J 0
(-6800 4425);
DISPLAY INVISIBLE (-6800 4425);
FORCEPROP 1 LAST PATH I84
J 0
(-6750 4450);
DISPLAY 0.872340 (-6750 4450);
PAINT AQUA (-6750 4450);
DISPLAY INVISIBLE (-6750 4450);
FORCEADD Q_RES..1
(-6175 2100);
FORCEPROP 1 LAST LOCATION PR116
J 0
(-6225 2150);
DISPLAY 0.489362 (-6225 2150);
PAINT SKYBLUE (-6225 2150);
FORCEPROP 0 LAST $SEC 1
J 0
(-6225 2200);
DISPLAY 0.680851 (-6225 2200);
PAINT MONO (-6225 2200);
DISPLAY INVISIBLE (-6225 2200);
FORCEPROP 0 LAST CDS_SEC 1
J 0
(-6225 2200);
DISPLAY 1.021277 (-6225 2200);
DISPLAY INVISIBLE (-6225 2200);
FORCEPROP 1 LASTPIN (-6275 2100) $PN 1
J 0
(-6263 2112);
DISPLAY 0.489362 (-6263 2112);
PAINT MONO (-6263 2112);
FORCEPROP 1 LASTPIN (-6075 2100) $PN 2
J 0
(-6113 2112);
DISPLAY 0.489362 (-6113 2112);
PAINT MONO (-6113 2112);
FORCEPROP 1 LAST WATTAGE 1/16W
J 0
(-6075 2050);
DISPLAY 0.489362 (-6075 2050);
PAINT SKYBLUE (-6075 2050);
FORCEPROP 1 LAST MATERIAL EMPTY
J 0
(-6425 2025);
DISPLAY 0.489362 (-6425 2025);
PAINT RED (-6425 2025);
FORCEPROP 1 LAST TOLERANCE 5%
J 0
(-6050 2125);
DISPLAY 0.489362 (-6050 2125);
PAINT SKYBLUE (-6050 2125);
FORCEPROP 1 LAST VALUE 0
J 2
(-6300 2125);
DISPLAY 0.489362 (-6300 2125);
PAINT SKYBLUE (-6300 2125);
FORCEPROP 1 LAST PART_NUMBER CS00002JB38
J 0
(-6425 2050);
DISPLAY 0.489362 (-6425 2050);
PAINT SKYBLUE (-6425 2050);
FORCEPROP 1 LAST PACK_TYPE 0402LF
J 0
(-6075 2025);
DISPLAY 0.489362 (-6075 2025);
PAINT SKYBLUE (-6075 2025);
FORCEPROP 2 LAST CDS_LIB pure_quanta
J 0
(-6175 2100);
DISPLAY INVISIBLE (-6175 2100);
FORCEPROP 1 LAST PATH I94
J 0
(-6225 2250);
DISPLAY 0.978723 (-6225 2250);
PAINT WHITE (-6225 2250);
DISPLAY INVISIBLE (-6225 2250);
FORCEADD Q_RES..2
(-5900 2325);
FORCEPROP 1 LAST LOCATION PR124
J 0
(-5855 2450);
DISPLAY 0.489362 (-5855 2450);
PAINT SKYBLUE (-5855 2450);
FORCEPROP 0 LAST $SEC 1
J 0
(-5850 2500);
DISPLAY 0.680851 (-5850 2500);
PAINT MONO (-5850 2500);
DISPLAY INVISIBLE (-5850 2500);
FORCEPROP 0 LAST CDS_SEC 1
J 0
(-5850 2500);
DISPLAY 1.021277 (-5850 2500);
DISPLAY INVISIBLE (-5850 2500);
FORCEPROP 1 LASTPIN (-5900 2425) $PN 1
J 0
(-5895 2387);
DISPLAY 0.489362 (-5895 2387);
PAINT MONO (-5895 2387);
FORCEPROP 1 LASTPIN (-5900 2225) $PN 2
J 0
(-5895 2235);
DISPLAY 0.489362 (-5895 2235);
PAINT MONO (-5895 2235);
FORCEPROP 1 LAST WATTAGE 1/16W
J 0
(-5860 2300);
DISPLAY 0.489362 (-5860 2300);
PAINT SKYBLUE (-5860 2300);
FORCEPROP 1 LAST MATERIAL EMPTY
J 0
(-5860 2250);
DISPLAY 0.489362 (-5860 2250);
PAINT RED (-5860 2250);
FORCEPROP 1 LAST TOLERANCE 1%
J 0
(-5855 2350);
DISPLAY 0.489362 (-5855 2350);
PAINT SKYBLUE (-5855 2350);
FORCEPROP 1 LAST VALUE 1K
J 0
(-5855 2400);
DISPLAY 0.489362 (-5855 2400);
PAINT SKYBLUE (-5855 2400);
FORCEPROP 1 LAST PART_NUMBER TMP_QCS21002FB24
J 0
(-5860 2200);
DISPLAY 0.489362 (-5860 2200);
PAINT SKYBLUE (-5860 2200);
FORCEPROP 1 LAST PACK_TYPE 0402LF
J 0
(-5860 2150);
DISPLAY 0.489362 (-5860 2150);
PAINT SKYBLUE (-5860 2150);
FORCEPROP 2 LAST CDS_LIB pure_quanta
J 0
(-5900 2325);
DISPLAY INVISIBLE (-5900 2325);
FORCEPROP 1 LAST PATH I95
J 0
(-5850 2500);
DISPLAY 0.978723 (-5850 2500);
PAINT WHITE (-5850 2500);
DISPLAY INVISIBLE (-5850 2500);
FORCEADD VCC_CORE..1
(-5900 2525);
FORCEPROP 3 LASTPIN (-5900 2475) SIG_NAME PVDD18_S5_P0\g
J 0
(-5890 2485);
DISPLAY 0.659574 (-5890 2485);
PAINT MONO (-5890 2485);
DISPLAY INVISIBLE (-5890 2485);
FORCEPROP 1 LAST HDL_POWER PVDD18_S5_P0
J 1
(-5900 2575);
DISPLAY 0.489362 (-5900 2575);
PAINT GREEN (-5900 2575);
FORCEPROP 2 LAST CDS_LIB pure_quanta_power
J 0
(-5900 2525);
DISPLAY INVISIBLE (-5900 2525);
FORCEPROP 1 LAST PATH I96
J 0
(-5850 2550);
DISPLAY 0.872340 (-5850 2550);
PAINT AQUA (-5850 2550);
DISPLAY INVISIBLE (-5850 2550);
FORCEADD OFFPAGE..2
R 2
(-6925 2100);
FORCEPROP 2 LAST $XR0 81 
J 0
(-7179 2100);
DISPLAY 0.638298 (-7179 2100);
PAINT MONO (-7179 2100);
FORCEPROP 2 LAST PATH I97
J 0
(-6875 2175);
DISPLAY 1.021277 (-6875 2175);
DISPLAY INVISIBLE (-6875 2175);
FORCEPROP 2 LAST CDS_LIB standard
J 0
(-6925 2100);
DISPLAY INVISIBLE (-6925 2100);
FORCEPROP 1 LAST COMMENT_BODY TRUE
J 2
(-6880 2005);
DISPLAY 0.872340 (-6880 2005);
PAINT GREEN (-6880 2005);
DISPLAY INVISIBLE (-6880 2005);
FORCEPROP 1 LAST OFFPAGE TRUE
J 2
(-7250 1975);
DISPLAY 0.872340 (-7250 1975);
PAINT GREEN (-7250 1975);
DISPLAY INVISIBLE (-7250 1975);
FORCEADD UNIVERSAL_GND..1
(-5100 450);
FORCEPROP 3 LASTPIN (-5100 500) SIG_NAME GND\g
J 0
(-5090 510);
DISPLAY 0.659574 (-5090 510);
PAINT MONO (-5090 510);
DISPLAY INVISIBLE (-5090 510);
FORCEPROP 2 LAST CDS_LIB pure_quanta_power
J 0
(-5100 450);
DISPLAY INVISIBLE (-5100 450);
FORCEPROP 1 LAST PATH I99
J 0
(-5025 450);
DISPLAY 0.872340 (-5025 450);
PAINT AQUA (-5025 450);
DISPLAY INVISIBLE (-5025 450);
FORCEPROP 1 LAST HDL_POWER GND
J 1
(-5075 375);
DISPLAY 0.872340 (-5075 375);
PAINT GREEN (-5075 375);
DISPLAY INVISIBLE (-5075 375);
FORCEADD DNS..1
(-2075 1375);
PAINT RED (-2075 1375);
FORCEPROP 2 LAST CDS_LIB mstr_misc
J 0
(-2075 1375);
DISPLAY INVISIBLE (-2075 1375);
FORCEPROP 1 LAST COMMENT_BODY TRUE
R 1
J 0
(-2000 1150);
DISPLAY 0.872340 (-2000 1150);
PAINT GREEN (-2000 1150);
DISPLAY INVISIBLE (-2000 1150);
FORCEADD DNS..1
(-1650 1800);
PAINT RED (-1650 1800);
FORCEPROP 2 LAST CDS_LIB mstr_misc
J 0
(-1650 1800);
DISPLAY INVISIBLE (-1650 1800);
FORCEPROP 1 LAST COMMENT_BODY TRUE
R 1
J 0
(-1575 1575);
DISPLAY 0.872340 (-1575 1575);
PAINT GREEN (-1575 1575);
DISPLAY INVISIBLE (-1575 1575);
FORCEADD DNS..1
(-5250 6350);
PAINT RED (-5250 6350);
FORCEPROP 2 LAST CDS_LIB mstr_misc
J 0
(-5250 6350);
DISPLAY INVISIBLE (-5250 6350);
FORCEPROP 1 LAST COMMENT_BODY TRUE
R 1
J 0
(-5175 6125);
DISPLAY 0.872340 (-5175 6125);
PAINT GREEN (-5175 6125);
DISPLAY INVISIBLE (-5175 6125);
FORCEADD DNS..1
(-5600 450);
PAINT RED (-5600 450);
FORCEPROP 2 LAST CDS_LIB mstr_misc
J 0
(-5600 450);
DISPLAY INVISIBLE (-5600 450);
FORCEPROP 1 LAST COMMENT_BODY TRUE
R 1
J 0
(-5525 225);
DISPLAY 0.872340 (-5525 225);
PAINT GREEN (-5525 225);
DISPLAY INVISIBLE (-5525 225);
FORCEADD DNS..1
(-6125 1725);
PAINT RED (-6125 1725);
FORCEPROP 2 LAST CDS_LIB mstr_misc
J 0
(-6125 1725);
DISPLAY INVISIBLE (-6125 1725);
FORCEPROP 1 LAST COMMENT_BODY TRUE
R 1
J 0
(-6050 1500);
DISPLAY 0.872340 (-6050 1500);
PAINT GREEN (-6050 1500);
DISPLAY INVISIBLE (-6050 1500);
FORCEADD DNS..1
(-5900 2300);
PAINT RED (-5900 2300);
FORCEPROP 2 LAST CDS_LIB mstr_misc
J 0
(-5900 2300);
DISPLAY INVISIBLE (-5900 2300);
FORCEPROP 1 LAST COMMENT_BODY TRUE
R 1
J 0
(-5825 2075);
DISPLAY 0.872340 (-5825 2075);
PAINT GREEN (-5825 2075);
DISPLAY INVISIBLE (-5825 2075);
FORCEADD QUANTA_TITLE_BLOCK_C..1
(0 0);
FORCEPROP 0 LAST CDS_CON_LAST_MODIFIED Fri Mar 11 14:53:30 2022
J 0
(-1885 15);
DISPLAY INVISIBLE (-1885 15);
FORCEPROP 1 LAST CUSTOM_TXT_CDS <CON_LAST_MODIFIED>
J 0
(-1885 15);
DISPLAY 0.978723 (-1885 15);
FORCEPROP 2 LAST CUSTOM_TXT_CDS <XR_PAGE_TITLE>
J 0
(-7890 5250);
DISPLAY 0.638298 (-7890 5250);
PAINT PINK (-7890 5250);
DISPLAY INVISIBLE (-7890 5250);
FORCEPROP 1 LAST CUSTOM_TXT_CDS <NAME_2>
J 0
(-3175 50);
FORCEPROP 1 LAST CUSTOM_TXT_CDS <NAME_1>
J 0
(-3175 175);
FORCEPROP 1 LAST CUSTOM_TXT_CDS <Q_NUMBER>
J 0
(-1403 103);
DISPLAY 1.212766 (-1403 103);
FORCEPROP 1 LAST CUSTOM_TXT_CDS <Q_PROJ>
J 0
(-2382 102);
DISPLAY 1.212766 (-2382 102);
FORCEPROP 1 LAST CUSTOM_TXT_CDS <Q_REV>
J 0
(-184 103);
DISPLAY 1.212766 (-184 103);
FORCEPROP 1 LAST CUSTOM_TXT_CDS <CON_PAGE_NUM> OF <CON_TOTAL_PAGES>
J 0
(-446 18);
DISPLAY 0.978723 (-446 18);
FORCEPROP 1 LAST Q_TITLE PVDD11_S3_P0 VR CONTROLLER
J 0
(-9325 50);
DISPLAY 2.446809 (-9325 50);
PAINT GREEN (-9325 50);
FORCEPROP 1 LAST Q_DEPT BU9
J 1
(-3763 49);
DISPLAY 1.957447 (-3763 49);
PAINT GREEN (-3763 49);
FORCEPROP 1 LAST CDS_LMAN_SYM_OUTLINE -9475,6775,100,-125
J 0
(0 0);
DISPLAY 0.468085 (0 0);
PAINT GREEN (0 0);
DISPLAY INVISIBLE (0 0);
FORCEPROP 2 LAST CDS_LIB pure_quanta
J 0
(0 0);
DISPLAY INVISIBLE (0 0);
FORCEPROP 2 LAST PAGE_BORDER TRUE
J 0
(-7890 5250);
DISPLAY 0.638298 (-7890 5250);
PAINT PINK (-7890 5250);
DISPLAY INVISIBLE (-7890 5250);
FORCEPROP 1 LAST COMMENT_BODY TRUE
J 0
(12 -13);
DISPLAY 0.978723 (12 -13);
PAINT GREEN (12 -13);
DISPLAY INVISIBLE (12 -13);
FORCEPROP 2 LAST CDS_XR_PAGE_TITLE CR-183 : @T6G_MB_LIB.T6G(SCH_1):PAGE183
J 0
(-7890 5250);
DISPLAY 0.638298 (-7890 5250);
PAINT PINK (-7890 5250);
DISPLAY INVISIBLE (-7890 5250);
FORCEADD DNS..1
(-1600 1575);
PAINT RED (-1600 1575);
FORCEPROP 2 LAST CDS_LIB mstr_misc
J 0
(-1600 1575);
DISPLAY INVISIBLE (-1600 1575);
FORCEPROP 1 LAST COMMENT_BODY TRUE
R 1
J 0
(-1525 1350);
DISPLAY 0.872340 (-1525 1350);
PAINT GREEN (-1525 1350);
DISPLAY INVISIBLE (-1525 1350);
FORCEADD DNS..1
(-6175 2075);
PAINT RED (-6175 2075);
FORCEPROP 2 LAST CDS_LIB mstr_misc
J 0
(-6175 2075);
DISPLAY INVISIBLE (-6175 2075);
FORCEPROP 1 LAST COMMENT_BODY TRUE
R 1
J 0
(-6100 1850);
DISPLAY 0.872340 (-6100 1850);
PAINT GREEN (-6100 1850);
DISPLAY INVISIBLE (-6100 1850);
WIRE 16 -1 (-2925 5975)(-2925 6025);
WIRE 16 -1 (-5300 375)(-5300 300);
WIRE 16 -1 (-6450 550)(-6450 425);
WIRE 16 -1 (-6875 550)(-6875 450);
WIRE 16 -1 (-2925 5475)(-2925 5550);
WIRE 16 -1 (-3325 5525)(-3325 5475);
WIRE 16 -1 (-3325 6025)(-3325 5925);
WIRE 16 -1 (-2600 1200)(-2600 1175);
WIRE 16 -1 (-2950 1200)(-2600 1200);
WIRE 16 -1 (-2075 1300)(-2075 1225);
WIRE 16 -1 (-2925 4100)(-2600 4100);
WIRE 16 -1 (-2600 4100)(-2600 4075);
WIRE 16 -1 (-2600 3650)(-2600 3625);
WIRE 16 -1 (-2950 3650)(-2600 3650);
WIRE 16 -1 (-2600 3200)(-2600 3175);
WIRE 16 -1 (-2950 3200)(-2600 3200);
WIRE 16 -1 (-2600 2750)(-2600 2725);
WIRE 16 -1 (-2950 2750)(-2600 2750);
WIRE 16 -1 (-2600 2300)(-2600 2275);
WIRE 16 -1 (-2950 2300)(-2600 2300);
WIRE 16 -1 (-2600 1850)(-2600 1825);
WIRE 16 -1 (-2950 1850)(-2600 1850);
WIRE 16 -1 (-5625 350)(-5625 300);
WIRE 16 -1 (-3375 600)(-3375 475);
WIRE 16 -1 (-5600 1100)(-5600 1150);
WIRE 16 -1 (-6800 3550)(-6800 3525);
WIRE 16 -1 (-6800 4325)(-6800 4375);
WIRE 16 -1 (-5900 2425)(-5900 2475);
WIRE 16 -1 (-5675 3825)(-5675 3800);
WIRE 16 -1 (-5675 3800)(-5025 3800);
WIRE 16 -1 (-5675 3800)(-6800 3800);
WIRE 16 -1 (-7425 3800)(-6800 3800);
FORCEPROP 2 LAST SIG_NAME VSENSE_VSS_SENSE_C_P0
J 2
(-6835 3810);
DISPLAY 0.489362 (-6835 3810);
WIRE 16 -1 (-6800 3750)(-6800 3800);
WIRE 16 -1 (-7425 4050)(-6800 4050);
FORCEPROP 2 LAST SIG_NAME VSENSE_PVDD11_S3_P0_DP
J 2
(-6835 4060);
DISPLAY 0.489362 (-6835 4060);
WIRE 16 -1 (-6800 4125)(-6800 4050);
WIRE 16 -1 (-6075 4050)(-6800 4050);
WIRE 16 -1 (-3675 2400)(-2850 2400);
FORCEPROP 2 LAST SIG_NAME NC_PVDD11_S3_P0_PWM7
J 2
(-3110 2410);
DISPLAY 0.489362 (-3110 2410);
FORCEPROP 2 LASTPROP $XRERR UNIQUE?
J 0
(-2820 2400);
DISPLAY 0.638298 (-2820 2400);
PAINT MONO (-2820 2400);
DISPLAY INVISIBLE (-2820 2400);
WIRE 16 -1 (-3150 2300)(-3675 2300);
FORCEPROP 2 LAST SIG_NAME NC_PVDD11_S3_P0_IMON7
J 2
(-3135 2310);
DISPLAY 0.489362 (-3135 2310);
FORCEPROP 2 LASTPROP $XRERR UNIQUE?
J 0
(-3375 2310);
DISPLAY 0.638298 (-3375 2310);
PAINT MONO (-3375 2310);
DISPLAY INVISIBLE (-3375 2310);
WIRE 16 -1 (-5025 1850)(-5750 1850);
FORCEPROP 2 LAST SIG_NAME PVDD11_S3_P0_VDDIO
J 2
(-5135 1860);
DISPLAY 0.489362 (-5135 1860);
FORCEPROP 2 LASTPROP $XRERR UNIQUE?
J 0
(-5375 1860);
DISPLAY 0.638298 (-5375 1860);
PAINT MONO (-5375 1860);
DISPLAY INVISIBLE (-5375 1860);
WIRE 16 -1 (-5750 1700)(-5750 1850);
WIRE 16 -1 (-6000 1700)(-5750 1700);
WIRE 17 273 (-1700 6575)(-1700 5625);
WIRE 17 273 (-1700 6575)(-100 6575);
WIRE 17 273 (-1700 5625)(-100 5625);
WIRE 17 273 (-100 6575)(-100 5625);
WIRE 16 -1 (-2125 6325)(-2125 6275);
WIRE 16 -1 (-2125 6275)(-2400 6275);
WIRE 16 -1 (-3675 6100)(-3450 6100);
WIRE 16 -1 (-3450 6100)(-3450 6275);
WIRE 16 -1 (-3450 6275)(-3325 6275);
WIRE 16 -1 (-3325 6275)(-2925 6275);
FORCEPROP 2 LAST SIG_NAME PVDD11_S3_P0_VCC
J 2
(-3010 6300);
DISPLAY 0.489362 (-3010 6300);
FORCEPROP 2 LASTPROP $XRERR UNIQUE?
J 0
(-3250 6300);
DISPLAY 0.638298 (-3250 6300);
PAINT MONO (-3250 6300);
DISPLAY INVISIBLE (-3250 6300);
WIRE 16 -1 (-3325 6275)(-3325 6225);
WIRE 16 -1 (-2600 6275)(-2925 6275);
WIRE 16 -1 (-2925 6225)(-2925 6275);
WIRE 16 -1 (-3675 5800)(-3325 5800);
WIRE 16 -1 (-3325 5800)(-2925 5800);
FORCEPROP 2 LAST SIG_NAME PVDD11_S3_P0_VCCS
J 2
(-3210 5810);
DISPLAY 0.489362 (-3210 5810);
WIRE 16 -1 (-3325 5800)(-3325 5725);
WIRE 16 -1 (-2775 5800)(-2925 5800);
WIRE 16 -1 (-2925 5750)(-2925 5800);
WIRE 16 -1 (-3675 4200)(-2850 4200);
FORCEPROP 2 LAST SIG_NAME NC_PVDD11_S3_P0_PWM3
J 2
(-3110 4210);
DISPLAY 0.489362 (-3110 4210);
FORCEPROP 2 LASTPROP $XRERR UNIQUE?
J 0
(-2820 4200);
DISPLAY 0.638298 (-2820 4200);
PAINT MONO (-2820 4200);
DISPLAY INVISIBLE (-2820 4200);
WIRE 16 -1 (-3675 5000)(-3075 5000);
FORCEPROP 2 LAST SIG_NAME PVDD11_S3_P0_IMON1
J 2
(-3185 5010);
DISPLAY 0.489362 (-3185 5010);
WIRE 16 -1 (-3675 5100)(-3075 5100);
FORCEPROP 2 LAST SIG_NAME PVDD11_S3_P0_PWM1
J 2
(-3210 5110);
DISPLAY 0.489362 (-3210 5110);
WIRE 16 -1 (-800 1600)(-1500 1600);
FORCEPROP 2 LAST SIG_NAME PVDD11_S3_P0_RESET_N
J 2
(-810 1610);
DISPLAY 0.489362 (-810 1610);
WIRE 16 -1 (-1300 1925)(-1300 1825);
WIRE 16 -1 (-1300 1825)(-1550 1825);
WIRE 16 -1 (-3675 2850)(-2850 2850);
FORCEPROP 2 LAST SIG_NAME NC_PVDD11_S3_P0_PWM6
J 2
(-3110 2860);
DISPLAY 0.489362 (-3110 2860);
FORCEPROP 2 LASTPROP $XRERR UNIQUE?
J 0
(-2820 2850);
DISPLAY 0.638298 (-2820 2850);
PAINT MONO (-2820 2850);
DISPLAY INVISIBLE (-2820 2850);
WIRE 16 -1 (-3675 3750)(-2850 3750);
FORCEPROP 2 LAST SIG_NAME NC_PVDD11_S3_P0_PWM4
J 2
(-3110 3760);
DISPLAY 0.489362 (-3110 3760);
FORCEPROP 2 LASTPROP $XRERR UNIQUE?
J 0
(-2820 3750);
DISPLAY 0.638298 (-2820 3750);
PAINT MONO (-2820 3750);
DISPLAY INVISIBLE (-2820 3750);
WIRE 16 -1 (-3150 3200)(-3675 3200);
FORCEPROP 2 LAST SIG_NAME NC_PVDD11_S3_P0_IMON5
J 2
(-3135 3210);
DISPLAY 0.489362 (-3135 3210);
FORCEPROP 2 LASTPROP $XRERR UNIQUE?
J 0
(-3375 3210);
DISPLAY 0.638298 (-3375 3210);
PAINT MONO (-3375 3210);
DISPLAY INVISIBLE (-3375 3210);
WIRE 16 -1 (-3150 3650)(-3675 3650);
FORCEPROP 2 LAST SIG_NAME NC_PVDD11_S3_P0_IMON4
J 2
(-3135 3660);
DISPLAY 0.489362 (-3135 3660);
FORCEPROP 2 LASTPROP $XRERR UNIQUE?
J 0
(-3375 3660);
DISPLAY 0.638298 (-3375 3660);
PAINT MONO (-3375 3660);
DISPLAY INVISIBLE (-3375 3660);
WIRE 16 -1 (-3150 2750)(-3675 2750);
FORCEPROP 2 LAST SIG_NAME NC_PVDD11_S3_P0_IMON6
J 2
(-3135 2760);
DISPLAY 0.489362 (-3135 2760);
FORCEPROP 2 LASTPROP $XRERR UNIQUE?
J 0
(-3375 2760);
DISPLAY 0.638298 (-3375 2760);
PAINT MONO (-3375 2760);
DISPLAY INVISIBLE (-3375 2760);
WIRE 16 -1 (-3150 1850)(-3675 1850);
FORCEPROP 2 LAST SIG_NAME NC_PVDD11_S3_P0_IMON8
J 2
(-3135 1860);
DISPLAY 0.489362 (-3135 1860);
FORCEPROP 2 LASTPROP $XRERR UNIQUE?
J 0
(-3375 1860);
DISPLAY 0.638298 (-3375 1860);
PAINT MONO (-3375 1860);
DISPLAY INVISIBLE (-3375 1860);
WIRE 16 -1 (-3150 1200)(-3675 1200);
FORCEPROP 2 LAST SIG_NAME PVDD11_S3_P0_TEMP1
J 2
(-3160 1210);
DISPLAY 0.489362 (-3160 1210);
FORCEPROP 2 LASTPROP $XRERR UNIQUE?
J 0
(-3400 1210);
DISPLAY 0.638298 (-3400 1210);
PAINT MONO (-3400 1210);
DISPLAY INVISIBLE (-3400 1210);
WIRE 16 -1 (-3100 900)(-3375 900);
FORCEPROP 2 LAST SIG_NAME PVDD11_S3_P0_TEMP0
J 2
(-3160 910);
DISPLAY 0.489362 (-3160 910);
WIRE 16 -1 (-3375 800)(-3375 900);
WIRE 16 -1 (-3375 900)(-3675 900);
WIRE 16 -1 (-5000 6350)(-5000 6375);
WIRE 16 -1 (-5000 6375)(-5150 6375);
WIRE 16 -1 (-5625 6375)(-5625 6100);
WIRE 16 -1 (-5625 6375)(-5350 6375);
WIRE 16 -1 (-6025 6375)(-5625 6375);
WIRE 16 -1 (-5625 6100)(-5025 6100);
FORCEPROP 2 LAST SIG_NAME PWRGD_PVDD11_S3_P0_R
J 2
(-5135 6110);
DISPLAY 0.489362 (-5135 6110);
FORCEPROP 2 LASTPROP $XRERR UNIQUE?
J 0
(-5375 6110);
DISPLAY 0.638298 (-5375 6110);
PAINT MONO (-5375 6110);
DISPLAY INVISIBLE (-5375 6110);
WIRE 16 -1 (-5625 6100)(-5800 6100);
WIRE 16 -1 (-5000 5800)(-5000 5825);
WIRE 16 -1 (-5000 5825)(-5125 5825);
WIRE 16 -1 (-5025 5650)(-5975 5650);
WIRE 16 -1 (-5975 5650)(-5975 5500);
WIRE 16 -1 (-5975 5500)(-5025 5500);
WIRE 16 -1 (-5975 5500)(-5975 5200);
WIRE 16 -1 (-5975 5150)(-5975 5200);
WIRE 16 -1 (-5975 5200)(-5025 5200);
WIRE 16 -1 (-5025 4800)(-5875 4800);
FORCEPROP 2 LAST SIG_NAME PVDD11_S3_P0_PMSDA_R
J 2
(-5160 4810);
DISPLAY 0.489362 (-5160 4810);
FORCEPROP 2 LASTPROP $XRERR UNIQUE?
J 0
(-5400 4810);
DISPLAY 0.638298 (-5400 4810);
PAINT MONO (-5400 4810);
DISPLAY INVISIBLE (-5400 4810);
WIRE 16 -1 (-5025 5350)(-5725 5350);
FORCEPROP 2 LAST SIG_NAME NC_PVDD11_S3_P0_SVTO
J 2
(-5210 5360);
DISPLAY 0.489362 (-5210 5360);
FORCEPROP 2 LASTPROP $XRERR UNIQUE?
J 0
(-5965 5350);
DISPLAY 0.638298 (-5965 5350);
PAINT MONO (-5965 5350);
DISPLAY INVISIBLE (-5965 5350);
WIRE 16 -1 (-5025 4950)(-5875 4950);
FORCEPROP 2 LAST SIG_NAME PVDD11_S3_P0_PMSCL_R
J 2
(-5160 4960);
DISPLAY 0.489362 (-5160 4960);
FORCEPROP 2 LASTPROP $XRERR UNIQUE?
J 0
(-5400 4960);
DISPLAY 0.638298 (-5400 4960);
PAINT MONO (-5400 4960);
DISPLAY INVISIBLE (-5400 4960);
WIRE 16 -1 (-5875 4650)(-5025 4650);
FORCEPROP 2 LAST SIG_NAME PVDD11_S3_P0_PMALERT_R
J 2
(-5110 4660);
DISPLAY 0.489362 (-5110 4660);
FORCEPROP 2 LASTPROP $XRERR UNIQUE?
J 0
(-5350 4660);
DISPLAY 0.638298 (-5350 4660);
PAINT MONO (-5350 4660);
DISPLAY INVISIBLE (-5350 4660);
WIRE 16 -1 (-5325 5825)(-5625 5825);
WIRE 16 -1 (-5625 5825)(-5625 5950);
WIRE 16 -1 (-5625 5950)(-5025 5950);
FORCEPROP 2 LAST SIG_NAME PVDD11_S3_P0_EN_R
J 2
(-5135 5960);
DISPLAY 0.489362 (-5135 5960);
FORCEPROP 2 LASTPROP $XRERR UNIQUE?
J 0
(-5375 5960);
DISPLAY 0.638298 (-5375 5960);
PAINT MONO (-5375 5960);
DISPLAY INVISIBLE (-5375 5960);
WIRE 16 -1 (-5800 5950)(-5625 5950);
WIRE 16 -1 (-6075 4650)(-6700 4650);
FORCEPROP 2 LAST SIG_NAME PVDD11_S3_P0_PMALERT
J 2
(-6235 4660);
DISPLAY 0.489362 (-6235 4660);
WIRE 16 -1 (-6075 4800)(-6700 4800);
FORCEPROP 2 LAST SIG_NAME SMB_VR_3V3STBY_SDA
J 2
(-6285 4810);
DISPLAY 0.489362 (-6285 4810);
WIRE 16 -1 (-6075 4950)(-6700 4950);
FORCEPROP 2 LAST SIG_NAME SMB_VR_3V3STBY_SCL
J 2
(-6285 4960);
DISPLAY 0.489362 (-6285 4960);
WIRE 16 -1 (-6000 6100)(-6575 6100);
FORCEPROP 2 LAST SIG_NAME PWRGD_PVDD11_S3_P0
J 2
(-6185 6110);
DISPLAY 0.489362 (-6185 6110);
WIRE 16 -1 (-6000 5950)(-6575 5950);
FORCEPROP 2 LAST SIG_NAME PVDD11_S3_P0_EN
J 2
(-6210 5960);
DISPLAY 0.489362 (-6210 5960);
WIRE 16 -1 (-6525 6450)(-6525 6375);
WIRE 16 -1 (-6525 6375)(-6225 6375);
WIRE 17 273 (-7725 3650)(-7725 4200);
WIRE 17 273 (-7725 3650)(-7400 3650);
WIRE 17 273 (-7725 4200)(-7400 4200);
WIRE 17 273 (-7400 4200)(-7400 3650);
WIRE 16 -1 (-5875 4050)(-5675 4050);
WIRE 16 -1 (-5675 4050)(-5025 4050);
FORCEPROP 2 LAST SIG_NAME VSENSE_PVDD11_S3_P0_R
J 2
(-5135 4060);
DISPLAY 0.489362 (-5135 4060);
FORCEPROP 2 LASTPROP $XRERR UNIQUE?
J 0
(-5375 4060);
DISPLAY 0.638298 (-5375 4060);
PAINT MONO (-5375 4060);
DISPLAY INVISIBLE (-5375 4060);
WIRE 16 -1 (-5675 4025)(-5675 4050);
WIRE 16 -1 (-6075 2100)(-5900 2100);
WIRE 16 -1 (-5025 2100)(-5900 2100);
FORCEPROP 2 LAST SIG_NAME PVDD11_S3_P0_OCP_N_R
J 2
(-5135 2110);
DISPLAY 0.489362 (-5135 2110);
FORCEPROP 2 LASTPROP $XRERR UNIQUE?
J 0
(-5375 2110);
DISPLAY 0.638298 (-5375 2110);
PAINT MONO (-5375 2110);
DISPLAY INVISIBLE (-5375 2110);
WIRE 16 -1 (-5900 2225)(-5900 2100);
WIRE 16 -1 (-5025 2950)(-5300 2950);
WIRE 16 -1 (-5300 2950)(-5300 2700);
WIRE 16 -1 (-5300 2600)(-5300 2700);
WIRE 16 -1 (-5300 2700)(-5025 2700);
WIRE 16 -1 (-5100 500)(-5100 550);
WIRE 16 -1 (-5100 550)(-5025 550);
WIRE 16 -1 (-5025 850)(-5550 850);
FORCEPROP 2 LAST SIG_NAME NC_PVDD11_S3_P0_PG1
J 0
(-5560 860);
DISPLAY 0.489362 (-5560 860);
FORCEPROP 2 LASTPROP $XRERR UNIQUE?
J 0
(-5790 850);
DISPLAY 0.638298 (-5790 850);
PAINT MONO (-5790 850);
DISPLAY INVISIBLE (-5790 850);
WIRE 16 -1 (-5600 1400)(-5025 1400);
FORCEPROP 2 LAST SIG_NAME PVDD11_S3_P0_ADDR_CFG
J 2
(-5135 1410);
DISPLAY 0.489362 (-5135 1410);
FORCEPROP 2 LASTPROP $XRERR UNIQUE?
J 0
(-5375 1410);
DISPLAY 0.638298 (-5375 1410);
PAINT MONO (-5375 1410);
DISPLAY INVISIBLE (-5375 1410);
WIRE 16 -1 (-5600 1400)(-5600 1350);
WIRE 16 -1 (-5850 650)(-5625 650);
WIRE 16 -1 (-5625 650)(-5300 650);
WIRE 16 -1 (-5625 550)(-5625 650);
WIRE 16 -1 (-5025 650)(-5300 650);
FORCEPROP 2 LAST SIG_NAME PVDD11_S3_P0_VINSEN
J 2
(-5135 660);
DISPLAY 0.489362 (-5135 660);
FORCEPROP 2 LASTPROP $XRERR UNIQUE?
J 0
(-5375 660);
DISPLAY 0.638298 (-5375 660);
PAINT MONO (-5375 660);
DISPLAY INVISIBLE (-5375 660);
WIRE 16 -1 (-5300 575)(-5300 650);
WIRE 16 -1 (-6175 675)(-6175 650);
WIRE 16 -1 (-6050 650)(-6175 650);
WIRE 16 -1 (-6275 2100)(-6875 2100);
FORCEPROP 2 LAST SIG_NAME PVDD11_S3_P0_OCP_N
J 2
(-6410 2110);
DISPLAY 0.489362 (-6410 2110);
WIRE 16 -1 (-6525 1775)(-6525 1700);
WIRE 16 -1 (-6525 1700)(-6200 1700);
WIRE 16 -1 (-7100 825)(-6875 825);
WIRE 16 -1 (-6875 825)(-6450 825);
WIRE 16 -1 (-6875 750)(-6875 825);
WIRE 16 -1 (-5600 825)(-6450 825);
WIRE 16 -1 (-6450 750)(-6450 825);
WIRE 16 -1 (-5600 825)(-5600 750);
WIRE 16 -1 (-5600 750)(-5025 750);
FORCEPROP 2 LAST SIG_NAME PVDD11_S3_P0_VMON
J 2
(-5160 760);
DISPLAY 0.489362 (-5160 760);
FORCEPROP 2 LASTPROP $XRERR UNIQUE?
J 0
(-5400 760);
DISPLAY 0.638298 (-5400 760);
PAINT MONO (-5400 760);
DISPLAY INVISIBLE (-5400 760);
WIRE 16 -1 (-7550 875)(-7550 825);
WIRE 16 -1 (-7550 825)(-7300 825);
WIRE 16 -1 (-3675 1600)(-2075 1600);
FORCEPROP 2 LAST SIG_NAME PVDD11_S3_P0_RESET_N_R
J 2
(-2035 1610);
DISPLAY 0.489362 (-2035 1610);
FORCEPROP 2 LASTPROP $XRERR UNIQUE?
J 0
(-2275 1610);
DISPLAY 0.638298 (-2275 1610);
PAINT MONO (-2275 1610);
DISPLAY INVISIBLE (-2275 1610);
WIRE 16 -1 (-2075 1600)(-1975 1600);
WIRE 16 -1 (-2075 1600)(-2075 1500);
WIRE 16 -1 (-1975 1600)(-1700 1600);
WIRE 16 -1 (-1975 1600)(-1975 1825);
WIRE 16 -1 (-1975 1825)(-1750 1825);
WIRE 16 -1 (-3675 1950)(-2850 1950);
FORCEPROP 2 LAST SIG_NAME NC_PVDD11_S3_P0_PWM8
J 2
(-3110 1960);
DISPLAY 0.489362 (-3110 1960);
FORCEPROP 2 LASTPROP $XRERR UNIQUE?
J 0
(-2820 1950);
DISPLAY 0.638298 (-2820 1950);
PAINT MONO (-2820 1950);
DISPLAY INVISIBLE (-2820 1950);
WIRE 16 -1 (-3675 4650)(-3075 4650);
FORCEPROP 2 LAST SIG_NAME PVDD11_S3_P0_PWM2
J 2
(-3210 4660);
DISPLAY 0.489362 (-3210 4660);
WIRE 16 -1 (-3675 4550)(-3075 4550);
FORCEPROP 2 LAST SIG_NAME PVDD11_S3_P0_IMON2
J 2
(-3185 4560);
DISPLAY 0.489362 (-3185 4560);
WIRE 16 -1 (-3125 4100)(-3675 4100);
FORCEPROP 2 LAST SIG_NAME NC_PVDD11_S3_P0_IMON3
J 2
(-3110 4110);
DISPLAY 0.489362 (-3110 4110);
FORCEPROP 2 LASTPROP $XRERR UNIQUE?
J 0
(-3350 4110);
DISPLAY 0.638298 (-3350 4110);
PAINT MONO (-3350 4110);
DISPLAY INVISIBLE (-3350 4110);
WIRE 17 273 (-9075 625)(-7850 625);
WIRE 17 273 (-9075 625)(-9075 200);
WIRE 17 273 (-7850 625)(-7850 200);
WIRE 17 273 (-9075 200)(-7850 200);
WIRE 16 -1 (-3675 3300)(-2850 3300);
FORCEPROP 2 LAST SIG_NAME NC_PVDD11_S3_P0_PWM5
J 2
(-3110 3310);
DISPLAY 0.489362 (-3110 3310);
FORCEPROP 2 LASTPROP $XRERR UNIQUE?
J 0
(-2820 3300);
DISPLAY 0.638298 (-2820 3300);
PAINT MONO (-2820 3300);
DISPLAY INVISIBLE (-2820 3300);
DOT 1 (-2075 1600);
DOT 1 (-5625 650);
DOT 1 (-5300 650);
DOT 1 (-6875 825);
DOT 1 (-6450 825);
DOT 1 (-6800 3800);
DOT 1 (-6800 4050);
DOT 1 (-5900 2100);
DOT 1 (-5300 2700);
DOT 1 (-5675 3800);
DOT 1 (-5675 4050);
DOT 1 (-5975 5200);
DOT 1 (-5975 5500);
DOT 1 (-5625 6100);
DOT 1 (-5625 6375);
DOT 1 (-3375 900);
DOT 1 (-1975 1600);
DOT 1 (-3325 5800);
DOT 1 (-2925 5800);
DOT 1 (-3325 6275);
DOT 1 (-2925 6275);
DOT 1 (-5625 5950);
FORCENOTE
PU21=AR0T6GPV007
(-1800 4525) 0;
DISPLAY LEFT (-1800 4525);
DISPLAY 1.021277 (-1800 4525);
PAINT WHITE (-1800 4525);
FORCENOTE
PR126=CS22672FB12
(-1800 4450) 0;
DISPLAY LEFT (-1800 4450);
DISPLAY 1.021277 (-1800 4450);
PAINT WHITE (-1800 4450);
FORCENOTE
EFFICIENCY > 90% @TDC
(-1675 5700) 0;
DISPLAY LEFT (-1675 5700);
DISPLAY 0.936170 (-1675 5700);
PAINT WHITE (-1675 5700);
FORCENOTE
WORK FREQUENCY=600KHZ
(-1675 5775) 0;
DISPLAY LEFT (-1675 5775);
DISPLAY 0.936170 (-1675 5775);
PAINT WHITE (-1675 5775);
FORCENOTE
TRACE SPACING = 5MIL
(-7775 3400) 0;
DISPLAY LEFT (-7775 3400);
DISPLAY 0.808511 (-7775 3400);
PAINT WHITE (-7775 3400);
FORCENOTE
MAIN SOURCE:RENESAS BOM
(-1800 4850) 0;
DISPLAY LEFT (-1800 4850);
DISPLAY 1.021277 (-1800 4850);
PAINT WHITE (-1800 4850);
FORCENOTE
BOM NOTE
(-1800 4950) 0;
DISPLAY LEFT (-1800 4950);
DISPLAY 1.021277 (-1800 4950);
PAINT WHITE (-1800 4950);
FORCENOTE
LOAD RELEASE=35A
(-1675 5850) 0;
DISPLAY LEFT (-1675 5850);
DISPLAY 0.936170 (-1675 5850);
PAINT WHITE (-1675 5850);
FORCENOTE
LOAD STEP=25A
(-1675 5925) 0;
DISPLAY LEFT (-1675 5925);
DISPLAY 0.936170 (-1675 5925);
PAINT WHITE (-1675 5925);
FORCENOTE
OCP=96A (EDC*1.2)
(-1675 6000) 0;
DISPLAY LEFT (-1675 6000);
DISPLAY 0.936170 (-1675 6000);
PAINT WHITE (-1675 6000);
FORCENOTE
PVDD11_S3_P0 SPECFICATION
(-1675 6500) 0;
DISPLAY LEFT (-1675 6500);
DISPLAY 1.276596 (-1675 6500);
PAINT WHITE (-1675 6500);
FORCENOTE
TRACE WIDTH = 10MIL
(-7775 3475) 0;
DISPLAY LEFT (-7775 3475);
DISPLAY 0.808511 (-7775 3475);
PAINT WHITE (-7775 3475);
FORCENOTE
DIFFERENTIAL PAIR
(-7775 3550) 0;
DISPLAY LEFT (-7775 3550);
DISPLAY 0.808511 (-7775 3550);
PAINT WHITE (-7775 3550);
FORCENOTE
ADDRESS
(-8550 550) 0;
DISPLAY LEFT (-8550 550);
DISPLAY 0.808511 (-8550 550);
PAINT WHITE (-8550 550);
FORCENOTE
EDC=80A
(-1675 6075) 0;
DISPLAY LEFT (-1675 6075);
DISPLAY 0.936170 (-1675 6075);
PAINT WHITE (-1675 6075);
FORCENOTE
TDC=65A
(-1675 6150) 0;
DISPLAY LEFT (-1675 6150);
DISPLAY 0.936170 (-1675 6150);
PAINT WHITE (-1675 6150);
FORCENOTE
RIPPLE=+/-10MV
(-1675 6300) 0;
DISPLAY LEFT (-1675 6300);
DISPLAY 0.936170 (-1675 6300);
PAINT WHITE (-1675 6300);
FORCENOTE
OUTPUT VOLTAGE=1.1V+/-4%
(-1675 6375) 0;
DISPLAY LEFT (-1675 6375);
DISPLAY 0.936170 (-1675 6375);
PAINT WHITE (-1675 6375);
FORCENOTE
DC & AC=1.055-1.145V
(-1675 6225) 0;
DISPLAY LEFT (-1675 6225);
DISPLAY 0.936170 (-1675 6225);
PAINT WHITE (-1675 6225);
FORCENOTE
PR3=CS00002JB38
(-1800 3350) 0;
DISPLAY LEFT (-1800 3350);
DISPLAY 1.021277 (-1800 3350);
PAINT WHITE (-1800 3350);
FORCENOTE
PR125=CS37502FB05
(-1800 3200) 0;
DISPLAY LEFT (-1800 3200);
DISPLAY 1.021277 (-1800 3200);
PAINT WHITE (-1800 3200);
FORCENOTE
2ND SOURCE:INFENEON BOM
(-1800 4600) 0;
DISPLAY LEFT (-1800 4600);
DISPLAY 1.021277 (-1800 4600);
PAINT WHITE (-1800 4600);
FORCENOTE
PU21=AR0T6GPV006
(-1800 4775) 0;
DISPLAY LEFT (-1800 4775);
DISPLAY 1.021277 (-1800 4775);
PAINT WHITE (-1800 4775);
FORCENOTE
PMBUS ADDRESS AND CONFIG
(-9100 675) 0;
DISPLAY LEFT (-9100 675);
DISPLAY 1.170213 (-9100 675);
PAINT WHITE (-9100 675);
FORCENOTE
CONFIG/R
(-8200 550) 0;
DISPLAY LEFT (-8200 550);
DISPLAY 0.808511 (-8200 550);
PAINT WHITE (-8200 550);
FORCENOTE
RENESAS
(-9000 250) 0;
DISPLAY LEFT (-9000 250);
DISPLAY 0.638298 (-9000 250);
PAINT WHITE (-9000 250);
FORCENOTE
0X63
(-8550 450) 0;
DISPLAY LEFT (-8550 450);
DISPLAY 0.638298 (-8550 450);
PAINT WHITE (-8550 450);
FORCENOTE
/2.67K
(-8200 350) 0;
DISPLAY LEFT (-8200 350);
DISPLAY 0.638298 (-8200 350);
PAINT WHITE (-8200 350);
FORCENOTE
0X4B
(-8550 250) 0;
DISPLAY LEFT (-8550 250);
DISPLAY 0.638298 (-8550 250);
PAINT WHITE (-8550 250);
FORCENOTE
0X4B
(-8550 350) 0;
DISPLAY LEFT (-8550 350);
DISPLAY 0.638298 (-8550 350);
PAINT WHITE (-8550 350);
FORCENOTE
/34K
(-8200 250) 0;
DISPLAY LEFT (-8200 250);
DISPLAY 0.638298 (-8200 250);
PAINT WHITE (-8200 250);
FORCENOTE
0/3.09K
(-8200 450) 0;
DISPLAY LEFT (-8200 450);
DISPLAY 0.638298 (-8200 450);
PAINT WHITE (-8200 450);
FORCENOTE
RENESAS
(-9000 350) 0;
DISPLAY LEFT (-9000 350);
DISPLAY 0.638298 (-9000 350);
PAINT WHITE (-9000 350);
FORCENOTE
RENESAS
(-9000 450) 0;
DISPLAY LEFT (-9000 450);
DISPLAY 0.638298 (-9000 450);
PAINT WHITE (-9000 450);
FORCENOTE
VR
(-9000 550) 0;
DISPLAY LEFT (-9000 550);
DISPLAY 0.808511 (-9000 550);
PAINT WHITE (-9000 550);
FORCENOTE
PR601=CS24992FB07
(-1800 3050) 0;
DISPLAY LEFT (-1800 3050);
DISPLAY 1.021277 (-1800 3050);
PAINT WHITE (-1800 3050);
FORCENOTE
PC5=TMP_QCH21006JB10
(-1800 3125) 0;
DISPLAY LEFT (-1800 3125);
DISPLAY 1.021277 (-1800 3125);
PAINT WHITE (-1800 3125);
FORCENOTE
PC198=TMP_QCH31004KB17
(-1800 3275) 0;
DISPLAY LEFT (-1800 3275);
DISPLAY 1.021277 (-1800 3275);
PAINT WHITE (-1800 3275);
FORCENOTE
PC194,PR113,PC193 =EMPTY
(-1800 3425) 0;
DISPLAY LEFT (-1800 3425);
DISPLAY 1.021277 (-1800 3425);
PAINT WHITE (-1800 3425);
FORCENOTE
PR37,PR33,PR34,PR35,PR419,PR36=EMPTY
(-1800 3500) 0;
DISPLAY LEFT (-1800 3500);
DISPLAY 1.021277 (-1800 3500);
PAINT WHITE (-1800 3500);
FORCENOTE
PR126=CS33402FB06
(-1800 3575) 0;
DISPLAY LEFT (-1800 3575);
DISPLAY 1.021277 (-1800 3575);
PAINT WHITE (-1800 3575);
FORCENOTE
PU21=AL002856000
(-1800 3650) 0;
DISPLAY LEFT (-1800 3650);
DISPLAY 1.021277 (-1800 3650);
PAINT WHITE (-1800 3650);
FORCENOTE
3RD SOURCE:MPS BOM
(-1800 3725) 0;
DISPLAY LEFT (-1800 3725);
DISPLAY 1.021277 (-1800 3725);
PAINT WHITE (-1800 3725);
FORCENOTE
PR419,PR36,PR412 = EMPTY
(-1800 3925) 0;
DISPLAY LEFT (-1800 3925);
DISPLAY 1.021277 (-1800 3925);
PAINT WHITE (-1800 3925);
FORCENOTE
PR37,PR33,PR34,PR35 = EMPTY
(-1800 4000) 0;
DISPLAY LEFT (-1800 4000);
DISPLAY 1.021277 (-1800 4000);
PAINT WHITE (-1800 4000);
FORCENOTE
PR3 = CS21002FB24
(-1800 4075) 0;
DISPLAY LEFT (-1800 4075);
DISPLAY 1.021277 (-1800 4075);
PAINT WHITE (-1800 4075);
FORCENOTE
PR113 = CS25362FB15
(-1800 4150) 0;
DISPLAY LEFT (-1800 4150);
DISPLAY 1.021277 (-1800 4150);
PAINT WHITE (-1800 4150);
FORCENOTE
PC199 = CH5103KEB01
(-1800 4375) 0;
DISPLAY LEFT (-1800 4375);
DISPLAY 1.021277 (-1800 4375);
PAINT WHITE (-1800 4375);
FORCENOTE
PC194 = CH12206KB14
(-1800 4225) 0;
DISPLAY LEFT (-1800 4225);
DISPLAY 1.021277 (-1800 4225);
PAINT WHITE (-1800 4225);
FORCENOTE
PC198 = CH11006JB00
(-1800 4300) 0;
DISPLAY LEFT (-1800 4300);
DISPLAY 1.021277 (-1800 4300);
PAINT WHITE (-1800 4300);
FORCENOTE
PC193 = CH3104J1B00
(-1800 3850) 0;
DISPLAY LEFT (-1800 3850);
DISPLAY 1.021277 (-1800 3850);
PAINT WHITE (-1800 3850);
QUIT
